FILE_TYPE = MACRO_DRAWING;
SET COLOR_WIRE YELLOW;
SET COLOR_PROP ORANGE;
SET COLOR_DOT WHITE;
SET COLOR_ARC YELLOW;
SET COLOR_BODY GREEN;
SET COLOR_NOTE PURPLE;
SET PROP_DISPLAY VALUE;
SET PAGE_NUMBER P11;
SET PATH_NUMBER P256;
FORCEADD VCCAUX15..1
(1975 6625);
FORCEPROP 3 LASTPIN (1975 6575) SIG_NAME P3V3_AUX\g
J 0
(1985 6585);
DISPLAY 0.659574 (1985 6585);
PAINT MONO (1985 6585);
DISPLAY INVISIBLE (1985 6585);
FORCEPROP 1 LAST HDL_POWER P3V3_AUX
J 1
(1975 6675);
DISPLAY 0.702128 (1975 6675);
PAINT GREEN (1975 6675);
FORCEPROP 2 LAST CDS_LIB logical_power
J 0
(1975 6625);
DISPLAY INVISIBLE (1975 6625);
FORCEPROP 1 LAST PATH I101
J 0
(2025 6650);
DISPLAY 0.872340 (2025 6650);
PAINT AQUA (2025 6650);
DISPLAY INVISIBLE (2025 6650);
FORCEADD Q_RES..1
(-3325 3425);
FORCEPROP 1 LAST PACK_TYPE 0402LF
J 0
(-3225 3350);
DISPLAY 0.510638 (-3225 3350);
PAINT SKYBLUE (-3225 3350);
FORCEPROP 1 LAST VALUE 2K
J 2
(-3050 3425);
DISPLAY 0.510638 (-3050 3425);
PAINT SKYBLUE (-3050 3425);
FORCEPROP 1 LAST WATTAGE 1/16W
J 2
(-3375 3350);
DISPLAY 0.510638 (-3375 3350);
PAINT SKYBLUE (-3375 3350);
FORCEPROP 1 LAST MATERIAL CHIP
J 0
(-2975 3425);
DISPLAY 0.510638 (-2975 3425);
PAINT SKYBLUE (-2975 3425);
FORCEPROP 1 LAST TOLERANCE 1%
J 0
(-3325 3350);
DISPLAY 0.510638 (-3325 3350);
PAINT SKYBLUE (-3325 3350);
FORCEPROP 2 LAST CDS_LIB pure_quanta
J 0
(-3325 3425);
DISPLAY INVISIBLE (-3325 3425);
FORCEPROP 1 LAST PATH I110
J 0
(-3375 3575);
DISPLAY 0.978723 (-3375 3575);
PAINT WHITE (-3375 3575);
DISPLAY INVISIBLE (-3375 3575);
FORCEPROP 1 LAST PART_NUMBER CS22002FB07
J 0
(-3250 3450);
DISPLAY 0.510638 (-3250 3450);
PAINT WHITE (-3250 3450);
DISPLAY INVISIBLE (-3250 3450);
FORCEPROP 1 LAST LOCATION R75
J 0
(-3600 3425);
DISPLAY 0.702128 (-3600 3425);
PAINT YELLOW (-3600 3425);
FORCEPROP 0 LAST $SEC 1
J 0
(-3650 3500);
DISPLAY 0.680851 (-3650 3500);
PAINT MONO (-3650 3500);
DISPLAY INVISIBLE (-3650 3500);
FORCEPROP 0 LAST CDS_SEC 1
J 0
(-3650 3500);
DISPLAY 1.021277 (-3650 3500);
DISPLAY INVISIBLE (-3650 3500);
FORCEPROP 1 LASTPIN (-3425 3425) $PN 1
J 0
(-3413 3437);
DISPLAY 0.808511 (-3413 3437);
PAINT WHITE (-3413 3437);
DISPLAY INVISIBLE (-3413 3437);
FORCEPROP 1 LASTPIN (-3225 3425) $PN 2
J 0
(-3263 3437);
DISPLAY 0.808511 (-3263 3437);
PAINT WHITE (-3263 3437);
DISPLAY INVISIBLE (-3263 3437);
FORCEADD OFFPAGE..2
(-1675 3625);
FORCEPROP 2 LAST $XR1 12 
J 0
(-1396 3625);
DISPLAY 0.638298 (-1396 3625);
PAINT MONO (-1396 3625);
FORCEPROP 2 LAST $XR0 10 
J 0
(-1486 3625);
DISPLAY 0.638298 (-1486 3625);
PAINT MONO (-1486 3625);
FORCEPROP 2 LAST CDS_LIB standard
J 0
(-1675 3625);
DISPLAY INVISIBLE (-1675 3625);
FORCEPROP 1 LAST OFFPAGE TRUE
J 0
(-1350 3500);
DISPLAY 0.872340 (-1350 3500);
PAINT GREEN (-1350 3500);
DISPLAY INVISIBLE (-1350 3500);
FORCEPROP 1 LAST COMMENT_BODY TRUE
J 0
(-1720 3530);
DISPLAY 0.872340 (-1720 3530);
PAINT PEACH (-1720 3530);
DISPLAY INVISIBLE (-1720 3530);
FORCEPROP 2 LAST PATH I115
J 0
(-1425 3675);
DISPLAY 1.021277 (-1425 3675);
DISPLAY INVISIBLE (-1425 3675);
FORCEADD OFFPAGE..2
(-1675 3825);
FORCEPROP 2 LAST $XR0 12 
J 0
(-1486 3825);
DISPLAY 0.638298 (-1486 3825);
PAINT MONO (-1486 3825);
FORCEPROP 2 LAST $XR1 10 
J 0
(-1396 3825);
DISPLAY 0.638298 (-1396 3825);
PAINT MONO (-1396 3825);
FORCEPROP 2 LAST CDS_LIB standard
J 0
(-1675 3825);
DISPLAY INVISIBLE (-1675 3825);
FORCEPROP 1 LAST OFFPAGE TRUE
J 0
(-1350 3700);
DISPLAY 0.872340 (-1350 3700);
PAINT GREEN (-1350 3700);
DISPLAY INVISIBLE (-1350 3700);
FORCEPROP 1 LAST COMMENT_BODY TRUE
J 0
(-1720 3730);
DISPLAY 0.872340 (-1720 3730);
PAINT PEACH (-1720 3730);
DISPLAY INVISIBLE (-1720 3730);
FORCEPROP 2 LAST PATH I116
J 0
(-1425 3875);
DISPLAY 1.021277 (-1425 3875);
DISPLAY INVISIBLE (-1425 3875);
FORCEADD Q_RES..1
(-3325 3625);
FORCEPROP 1 LAST MATERIAL CHIP
J 0
(-2975 3625);
DISPLAY 0.510638 (-2975 3625);
PAINT SKYBLUE (-2975 3625);
FORCEPROP 1 LAST WATTAGE 1/16W
J 2
(-3375 3550);
DISPLAY 0.510638 (-3375 3550);
PAINT SKYBLUE (-3375 3550);
FORCEPROP 1 LAST TOLERANCE 1%
J 0
(-3325 3550);
DISPLAY 0.510638 (-3325 3550);
PAINT SKYBLUE (-3325 3550);
FORCEPROP 1 LAST PACK_TYPE 0402LF
J 0
(-3250 3550);
DISPLAY 0.510638 (-3250 3550);
PAINT SKYBLUE (-3250 3550);
FORCEPROP 1 LAST VALUE 2K
J 2
(-3050 3625);
DISPLAY 0.510638 (-3050 3625);
PAINT SKYBLUE (-3050 3625);
FORCEPROP 2 LAST CDS_LIB pure_quanta
J 0
(-3325 3625);
DISPLAY INVISIBLE (-3325 3625);
FORCEPROP 1 LAST PATH I117
J 0
(-3375 3775);
DISPLAY 0.978723 (-3375 3775);
PAINT WHITE (-3375 3775);
DISPLAY INVISIBLE (-3375 3775);
FORCEPROP 1 LAST PART_NUMBER CS22002FB07
J 0
(-3250 3650);
DISPLAY 0.510638 (-3250 3650);
PAINT WHITE (-3250 3650);
DISPLAY INVISIBLE (-3250 3650);
FORCEPROP 1 LAST LOCATION R74
J 0
(-3600 3625);
DISPLAY 0.702128 (-3600 3625);
PAINT YELLOW (-3600 3625);
FORCEPROP 0 LAST $SEC 1
J 0
(-3650 3700);
DISPLAY 0.680851 (-3650 3700);
PAINT MONO (-3650 3700);
DISPLAY INVISIBLE (-3650 3700);
FORCEPROP 0 LAST CDS_SEC 1
J 0
(-3650 3700);
DISPLAY 1.021277 (-3650 3700);
DISPLAY INVISIBLE (-3650 3700);
FORCEPROP 1 LASTPIN (-3425 3625) $PN 1
J 0
(-3413 3637);
DISPLAY 0.808511 (-3413 3637);
PAINT WHITE (-3413 3637);
DISPLAY INVISIBLE (-3413 3637);
FORCEPROP 1 LASTPIN (-3225 3625) $PN 2
J 0
(-3263 3637);
DISPLAY 0.808511 (-3263 3637);
PAINT WHITE (-3263 3637);
DISPLAY INVISIBLE (-3263 3637);
FORCEADD Q_RES..1
(-3350 3825);
FORCEPROP 1 LAST MATERIAL EMPTY
J 0
(-3000 3825);
DISPLAY 0.510638 (-3000 3825);
PAINT RED (-3000 3825);
FORCEPROP 1 LAST PACK_TYPE 0402LF
J 0
(-3300 3775);
DISPLAY 0.510638 (-3300 3775);
PAINT SKYBLUE (-3300 3775);
FORCEPROP 1 LAST WATTAGE 1/16W
J 2
(-3425 3775);
DISPLAY 0.510638 (-3425 3775);
PAINT SKYBLUE (-3425 3775);
FORCEPROP 1 LAST VALUE 1K
J 2
(-3075 3825);
DISPLAY 0.510638 (-3075 3825);
PAINT SKYBLUE (-3075 3825);
FORCEPROP 1 LAST TOLERANCE 1%
J 0
(-3400 3775);
DISPLAY 0.510638 (-3400 3775);
PAINT SKYBLUE (-3400 3775);
FORCEPROP 2 LAST CDS_LIB pure_quanta
J 0
(-3350 3825);
DISPLAY INVISIBLE (-3350 3825);
FORCEPROP 1 LAST PATH I118
J 0
(-3400 3975);
DISPLAY 0.978723 (-3400 3975);
PAINT WHITE (-3400 3975);
DISPLAY INVISIBLE (-3400 3975);
FORCEPROP 1 LAST PART_NUMBER CS21002FB06
J 0
(-3400 3925);
DISPLAY 0.510638 (-3400 3925);
PAINT WHITE (-3400 3925);
DISPLAY INVISIBLE (-3400 3925);
FORCEPROP 1 LAST LOCATION R73
J 0
(-3600 3825);
DISPLAY 0.702128 (-3600 3825);
PAINT YELLOW (-3600 3825);
FORCEPROP 0 LAST $SEC 1
J 0
(-3650 3875);
DISPLAY 0.680851 (-3650 3875);
PAINT MONO (-3650 3875);
DISPLAY INVISIBLE (-3650 3875);
FORCEPROP 0 LAST CDS_SEC 1
J 0
(-3650 3875);
DISPLAY 1.021277 (-3650 3875);
DISPLAY INVISIBLE (-3650 3875);
FORCEPROP 1 LASTPIN (-3450 3825) $PN 1
J 0
(-3438 3837);
DISPLAY 0.808511 (-3438 3837);
PAINT WHITE (-3438 3837);
DISPLAY INVISIBLE (-3438 3837);
FORCEPROP 1 LASTPIN (-3250 3825) $PN 2
J 0
(-3288 3837);
DISPLAY 0.808511 (-3288 3837);
PAINT WHITE (-3288 3837);
DISPLAY INVISIBLE (-3288 3837);
FORCEADD OFFPAGE..2
(-1675 4450);
FORCEPROP 2 LAST $XR1 10 
J 0
(-1396 4450);
DISPLAY 0.638298 (-1396 4450);
PAINT MONO (-1396 4450);
FORCEPROP 2 LAST $XR0 34 
J 0
(-1486 4450);
DISPLAY 0.638298 (-1486 4450);
PAINT MONO (-1486 4450);
FORCEPROP 2 LAST CDS_LIB standard
J 0
(-1675 4450);
DISPLAY INVISIBLE (-1675 4450);
FORCEPROP 1 LAST OFFPAGE TRUE
J 0
(-1350 4325);
DISPLAY 0.872340 (-1350 4325);
PAINT GREEN (-1350 4325);
DISPLAY INVISIBLE (-1350 4325);
FORCEPROP 1 LAST COMMENT_BODY TRUE
J 0
(-1720 4355);
DISPLAY 0.872340 (-1720 4355);
PAINT PEACH (-1720 4355);
DISPLAY INVISIBLE (-1720 4355);
FORCEPROP 2 LAST PATH I124
J 0
(-1425 4500);
DISPLAY 1.021277 (-1425 4500);
DISPLAY INVISIBLE (-1425 4500);
FORCEADD OFFPAGE..2
(-1675 4250);
FORCEPROP 2 LAST $XR0 10 
J 0
(-1486 4250);
DISPLAY 0.638298 (-1486 4250);
PAINT MONO (-1486 4250);
FORCEPROP 2 LAST $XR1 34 
J 0
(-1396 4250);
DISPLAY 0.638298 (-1396 4250);
PAINT MONO (-1396 4250);
FORCEPROP 2 LAST CDS_LIB standard
J 0
(-1675 4250);
DISPLAY INVISIBLE (-1675 4250);
FORCEPROP 1 LAST OFFPAGE TRUE
J 0
(-1350 4125);
DISPLAY 0.872340 (-1350 4125);
PAINT GREEN (-1350 4125);
DISPLAY INVISIBLE (-1350 4125);
FORCEPROP 1 LAST COMMENT_BODY TRUE
J 0
(-1720 4155);
DISPLAY 0.872340 (-1720 4155);
PAINT PEACH (-1720 4155);
DISPLAY INVISIBLE (-1720 4155);
FORCEPROP 2 LAST PATH I125
J 0
(-1425 4300);
DISPLAY 1.021277 (-1425 4300);
DISPLAY INVISIBLE (-1425 4300);
FORCEADD OFFPAGE..2
(-1675 4050);
FORCEPROP 2 LAST $XR0 34 
J 0
(-1486 4050);
DISPLAY 0.638298 (-1486 4050);
PAINT MONO (-1486 4050);
FORCEPROP 2 LAST $XR1 10 
J 0
(-1396 4050);
DISPLAY 0.638298 (-1396 4050);
PAINT MONO (-1396 4050);
FORCEPROP 2 LAST CDS_LIB standard
J 0
(-1675 4050);
DISPLAY INVISIBLE (-1675 4050);
FORCEPROP 1 LAST OFFPAGE TRUE
J 0
(-1350 3925);
DISPLAY 0.872340 (-1350 3925);
PAINT GREEN (-1350 3925);
DISPLAY INVISIBLE (-1350 3925);
FORCEPROP 1 LAST COMMENT_BODY TRUE
J 0
(-1720 3955);
DISPLAY 0.872340 (-1720 3955);
PAINT PEACH (-1720 3955);
DISPLAY INVISIBLE (-1720 3955);
FORCEPROP 2 LAST PATH I126
J 0
(-1350 4100);
DISPLAY 1.021277 (-1350 4100);
DISPLAY INVISIBLE (-1350 4100);
FORCEADD Q_RES..1
(-3325 4450);
FORCEPROP 1 LAST PACK_TYPE 0402LF
J 0
(-3250 4400);
DISPLAY 0.510638 (-3250 4400);
PAINT SKYBLUE (-3250 4400);
FORCEPROP 1 LAST MATERIAL EMPTY
J 0
(-2975 4450);
DISPLAY 0.510638 (-2975 4450);
PAINT RED (-2975 4450);
FORCEPROP 1 LAST TOLERANCE 1%
J 0
(-3350 4400);
DISPLAY 0.510638 (-3350 4400);
PAINT SKYBLUE (-3350 4400);
FORCEPROP 1 LAST WATTAGE 1/16W
J 2
(-3375 4400);
DISPLAY 0.510638 (-3375 4400);
PAINT SKYBLUE (-3375 4400);
FORCEPROP 1 LAST VALUE 1K
J 2
(-3050 4450);
DISPLAY 0.510638 (-3050 4450);
PAINT SKYBLUE (-3050 4450);
FORCEPROP 2 LAST CDS_LIB pure_quanta
J 0
(-3325 4450);
DISPLAY INVISIBLE (-3325 4450);
FORCEPROP 1 LAST PATH I128
J 0
(-3375 4600);
DISPLAY 0.978723 (-3375 4600);
PAINT WHITE (-3375 4600);
DISPLAY INVISIBLE (-3375 4600);
FORCEPROP 1 LAST PART_NUMBER CS21002FB06
J 0
(-3375 4550);
DISPLAY 0.510638 (-3375 4550);
PAINT WHITE (-3375 4550);
DISPLAY INVISIBLE (-3375 4550);
FORCEPROP 1 LAST LOCATION R77
J 0
(-3625 4450);
DISPLAY 0.702128 (-3625 4450);
PAINT YELLOW (-3625 4450);
FORCEPROP 0 LAST $SEC 1
J 0
(-3650 4550);
DISPLAY 0.680851 (-3650 4550);
PAINT MONO (-3650 4550);
DISPLAY INVISIBLE (-3650 4550);
FORCEPROP 0 LAST CDS_SEC 1
J 0
(-3650 4550);
DISPLAY 1.021277 (-3650 4550);
DISPLAY INVISIBLE (-3650 4550);
FORCEPROP 1 LASTPIN (-3425 4450) $PN 1
J 0
(-3413 4462);
DISPLAY 0.808511 (-3413 4462);
PAINT WHITE (-3413 4462);
DISPLAY INVISIBLE (-3413 4462);
FORCEPROP 1 LASTPIN (-3225 4450) $PN 2
J 0
(-3263 4462);
DISPLAY 0.808511 (-3263 4462);
PAINT WHITE (-3263 4462);
DISPLAY INVISIBLE (-3263 4462);
FORCEADD Q_RES..1
(-3325 4250);
FORCEPROP 1 LAST MATERIAL CHIP
J 0
(-2975 4250);
DISPLAY 0.510638 (-2975 4250);
PAINT SKYBLUE (-2975 4250);
FORCEPROP 1 LAST PACK_TYPE 0402LF
J 0
(-3250 4175);
DISPLAY 0.510638 (-3250 4175);
PAINT SKYBLUE (-3250 4175);
FORCEPROP 1 LAST TOLERANCE 1%
J 0
(-3325 4175);
DISPLAY 0.510638 (-3325 4175);
PAINT SKYBLUE (-3325 4175);
FORCEPROP 1 LAST WATTAGE 1/16W
J 2
(-3375 4175);
DISPLAY 0.510638 (-3375 4175);
PAINT SKYBLUE (-3375 4175);
FORCEPROP 1 LAST VALUE 2K
J 2
(-3050 4250);
DISPLAY 0.510638 (-3050 4250);
PAINT SKYBLUE (-3050 4250);
FORCEPROP 2 LAST CDS_LIB pure_quanta
J 0
(-3325 4250);
DISPLAY INVISIBLE (-3325 4250);
FORCEPROP 1 LAST PATH I129
J 0
(-3375 4400);
DISPLAY 0.978723 (-3375 4400);
PAINT WHITE (-3375 4400);
DISPLAY INVISIBLE (-3375 4400);
FORCEPROP 1 LAST PART_NUMBER CS22002FB07
J 0
(-3250 4275);
DISPLAY 0.510638 (-3250 4275);
PAINT WHITE (-3250 4275);
DISPLAY INVISIBLE (-3250 4275);
FORCEPROP 1 LAST LOCATION R78
J 0
(-3625 4250);
DISPLAY 0.702128 (-3625 4250);
PAINT YELLOW (-3625 4250);
FORCEPROP 0 LAST $SEC 1
J 0
(-3650 4325);
DISPLAY 0.680851 (-3650 4325);
PAINT MONO (-3650 4325);
DISPLAY INVISIBLE (-3650 4325);
FORCEPROP 0 LAST CDS_SEC 1
J 0
(-3650 4325);
DISPLAY 1.021277 (-3650 4325);
DISPLAY INVISIBLE (-3650 4325);
FORCEPROP 1 LASTPIN (-3425 4250) $PN 1
J 0
(-3413 4262);
DISPLAY 0.808511 (-3413 4262);
PAINT WHITE (-3413 4262);
DISPLAY INVISIBLE (-3413 4262);
FORCEPROP 1 LASTPIN (-3225 4250) $PN 2
J 0
(-3263 4262);
DISPLAY 0.808511 (-3263 4262);
PAINT WHITE (-3263 4262);
DISPLAY INVISIBLE (-3263 4262);
FORCEADD Q_RES..1
(-3325 4050);
FORCEPROP 1 LAST MATERIAL CHIP
J 0
(-2975 4050);
DISPLAY 0.510638 (-2975 4050);
PAINT SKYBLUE (-2975 4050);
FORCEPROP 1 LAST WATTAGE 1/16W
J 2
(-3375 3975);
DISPLAY 0.510638 (-3375 3975);
PAINT SKYBLUE (-3375 3975);
FORCEPROP 1 LAST VALUE 2K
J 2
(-3050 4050);
DISPLAY 0.510638 (-3050 4050);
PAINT SKYBLUE (-3050 4050);
FORCEPROP 1 LAST TOLERANCE 1%
J 0
(-3325 3975);
DISPLAY 0.510638 (-3325 3975);
PAINT SKYBLUE (-3325 3975);
FORCEPROP 1 LAST PACK_TYPE 0402LF
J 0
(-3250 3975);
DISPLAY 0.510638 (-3250 3975);
PAINT SKYBLUE (-3250 3975);
FORCEPROP 2 LAST CDS_LIB pure_quanta
J 0
(-3325 4050);
DISPLAY INVISIBLE (-3325 4050);
FORCEPROP 1 LAST PATH I130
J 0
(-3375 4200);
DISPLAY 0.978723 (-3375 4200);
PAINT WHITE (-3375 4200);
DISPLAY INVISIBLE (-3375 4200);
FORCEPROP 1 LAST PART_NUMBER CS22002FB07
J 0
(-3250 4075);
DISPLAY 0.510638 (-3250 4075);
PAINT WHITE (-3250 4075);
DISPLAY INVISIBLE (-3250 4075);
FORCEPROP 1 LAST LOCATION R79
J 2
(-3525 4050);
DISPLAY 0.702128 (-3525 4050);
PAINT YELLOW (-3525 4050);
FORCEPROP 0 LAST $SEC 1
J 0
(-3575 4100);
DISPLAY 0.680851 (-3575 4100);
PAINT MONO (-3575 4100);
DISPLAY INVISIBLE (-3575 4100);
FORCEPROP 0 LAST CDS_SEC 1
J 0
(-3575 4100);
DISPLAY 1.021277 (-3575 4100);
DISPLAY INVISIBLE (-3575 4100);
FORCEPROP 1 LASTPIN (-3425 4050) $PN 1
J 0
(-3413 4062);
DISPLAY 0.808511 (-3413 4062);
PAINT WHITE (-3413 4062);
DISPLAY INVISIBLE (-3413 4062);
FORCEPROP 1 LASTPIN (-3225 4050) $PN 2
J 0
(-3263 4062);
DISPLAY 0.808511 (-3263 4062);
PAINT WHITE (-3263 4062);
DISPLAY INVISIBLE (-3263 4062);
FORCEADD OFFPAGE..2
(-1675 6025);
FORCEPROP 2 LAST $XR1 10 
J 0
(-1396 6025);
DISPLAY 0.638298 (-1396 6025);
PAINT MONO (-1396 6025);
FORCEPROP 2 LAST $XR0 15 
J 0
(-1486 6025);
DISPLAY 0.638298 (-1486 6025);
PAINT MONO (-1486 6025);
FORCEPROP 2 LAST CDS_LIB standard
J 0
(-1675 6025);
DISPLAY INVISIBLE (-1675 6025);
FORCEPROP 1 LAST OFFPAGE TRUE
J 0
(-1350 5900);
DISPLAY 0.872340 (-1350 5900);
PAINT GREEN (-1350 5900);
DISPLAY INVISIBLE (-1350 5900);
FORCEPROP 1 LAST COMMENT_BODY TRUE
J 0
(-1720 5930);
DISPLAY 0.872340 (-1720 5930);
PAINT PEACH (-1720 5930);
DISPLAY INVISIBLE (-1720 5930);
FORCEPROP 2 LAST PATH I136
J 0
(-1500 6100);
DISPLAY 1.021277 (-1500 6100);
DISPLAY INVISIBLE (-1500 6100);
FORCEADD Q_RES..1
(-200 3625);
FORCEPROP 1 LAST MATERIAL EMPTY
J 0
(-200 3475);
DISPLAY 0.510638 (-200 3475);
PAINT RED (-200 3475);
FORCEPROP 1 LAST TOLERANCE 1%
J 0
(-200 3525);
DISPLAY 0.510638 (-200 3525);
PAINT SKYBLUE (-200 3525);
FORCEPROP 1 LAST PACK_TYPE 0402LF
J 0
(50 3475);
DISPLAY 0.510638 (50 3475);
PAINT SKYBLUE (50 3475);
FORCEPROP 1 LAST PART_NUMBER CS22002FB07
J 0
(-250 3725);
DISPLAY 0.510638 (-250 3725);
PAINT WHITE (-250 3725);
FORCEPROP 1 LAST VALUE 2K
J 2
(-225 3525);
DISPLAY 0.510638 (-225 3525);
PAINT SKYBLUE (-225 3525);
FORCEPROP 1 LAST WATTAGE 1/16W
J 2
(-225 3475);
DISPLAY 0.510638 (-225 3475);
PAINT SKYBLUE (-225 3475);
FORCEPROP 2 LAST CDS_LIB pure_quanta
J 0
(-200 3625);
DISPLAY INVISIBLE (-200 3625);
FORCEPROP 1 LAST PATH I171
J 0
(-250 3775);
DISPLAY 0.978723 (-250 3775);
PAINT WHITE (-250 3775);
DISPLAY INVISIBLE (-250 3775);
FORCEPROP 1 LAST LOCATION R40
J 0
(-575 3625);
DISPLAY 0.702128 (-575 3625);
PAINT YELLOW (-575 3625);
FORCEPROP 0 LAST $SEC 1
J 0
(-250 3750);
DISPLAY 0.680851 (-250 3750);
PAINT MONO (-250 3750);
DISPLAY INVISIBLE (-250 3750);
FORCEPROP 0 LAST CDS_SEC 1
J 0
(-550 3675);
DISPLAY INVISIBLE (-550 3675);
FORCEPROP 1 LASTPIN (-300 3625) $PN 1
J 0
(-288 3637);
DISPLAY 0.808511 (-288 3637);
PAINT WHITE (-288 3637);
DISPLAY INVISIBLE (-288 3637);
FORCEPROP 1 LASTPIN (-100 3625) $PN 2
J 0
(-138 3637);
DISPLAY 0.808511 (-138 3637);
PAINT WHITE (-138 3637);
DISPLAY INVISIBLE (-138 3637);
FORCEADD Q_RES..1
(-3325 6025);
FORCEPROP 1 LAST VALUE 4.7K
J 0
(-3150 6025);
DISPLAY 0.510638 (-3150 6025);
PAINT SKYBLUE (-3150 6025);
FORCEPROP 1 LAST MATERIAL EMPTY
J 0
(-2975 6025);
DISPLAY 0.510638 (-2975 6025);
PAINT RED (-2975 6025);
FORCEPROP 1 LAST PART_NUMBER CS24702FB06
J 0
(-3375 6125);
DISPLAY 0.510638 (-3375 6125);
PAINT WHITE (-3375 6125);
DISPLAY INVISIBLE (-3375 6125);
FORCEPROP 1 LAST PACK_TYPE 0402LF
J 0
(-3075 5875);
DISPLAY 0.510638 (-3075 5875);
PAINT SKYBLUE (-3075 5875);
DISPLAY INVISIBLE (-3075 5875);
FORCEPROP 1 LAST WATTAGE 1/16W
J 2
(-3350 5875);
DISPLAY 0.510638 (-3350 5875);
PAINT SKYBLUE (-3350 5875);
DISPLAY INVISIBLE (-3350 5875);
FORCEPROP 1 LAST PATH I175
J 0
(-3375 6175);
DISPLAY 0.978723 (-3375 6175);
PAINT WHITE (-3375 6175);
DISPLAY INVISIBLE (-3375 6175);
FORCEPROP 1 LAST TOLERANCE 1%
J 0
(-3325 5925);
DISPLAY 0.510638 (-3325 5925);
PAINT SKYBLUE (-3325 5925);
DISPLAY INVISIBLE (-3325 5925);
FORCEPROP 2 LAST CDS_LIB pure_quanta
J 0
(-3325 6025);
DISPLAY INVISIBLE (-3325 6025);
FORCEPROP 1 LAST LOCATION R44
J 0
(-3650 6025);
DISPLAY 0.702128 (-3650 6025);
PAINT YELLOW (-3650 6025);
FORCEPROP 0 LAST $SEC 1
J 0
(-3675 6075);
DISPLAY INVISIBLE (-3675 6075);
FORCEPROP 0 LAST CDS_SEC 1
J 0
(-3675 6075);
DISPLAY INVISIBLE (-3675 6075);
FORCEPROP 1 LASTPIN (-3425 6025) $PN 1
J 0
(-3413 6037);
DISPLAY 0.808511 (-3413 6037);
PAINT WHITE (-3413 6037);
DISPLAY INVISIBLE (-3413 6037);
FORCEPROP 1 LASTPIN (-3225 6025) $PN 2
J 0
(-3263 6037);
DISPLAY 0.808511 (-3263 6037);
PAINT WHITE (-3263 6037);
DISPLAY INVISIBLE (-3263 6037);
FORCEADD Q_RES..1
(-3325 5825);
FORCEPROP 1 LAST VALUE 4.7K
J 0
(-3150 5825);
DISPLAY 0.510638 (-3150 5825);
PAINT SKYBLUE (-3150 5825);
FORCEPROP 1 LAST MATERIAL CHIP
J 0
(-2975 5825);
DISPLAY 0.510638 (-2975 5825);
PAINT SKYBLUE (-2975 5825);
FORCEPROP 2 LAST CDS_LIB pure_quanta
J 0
(-3325 5825);
DISPLAY INVISIBLE (-3325 5825);
FORCEPROP 1 LAST TOLERANCE 1%
J 0
(-3325 5725);
DISPLAY 0.510638 (-3325 5725);
PAINT SKYBLUE (-3325 5725);
DISPLAY INVISIBLE (-3325 5725);
FORCEPROP 1 LAST PATH I176
J 0
(-3375 5975);
DISPLAY 0.978723 (-3375 5975);
PAINT WHITE (-3375 5975);
DISPLAY INVISIBLE (-3375 5975);
FORCEPROP 1 LAST WATTAGE 1/16W
J 2
(-3350 5675);
DISPLAY 0.510638 (-3350 5675);
PAINT SKYBLUE (-3350 5675);
DISPLAY INVISIBLE (-3350 5675);
FORCEPROP 1 LAST PACK_TYPE 0402LF
J 0
(-3075 5675);
DISPLAY 0.510638 (-3075 5675);
PAINT SKYBLUE (-3075 5675);
DISPLAY INVISIBLE (-3075 5675);
FORCEPROP 1 LAST PART_NUMBER CS24702FB06
J 0
(-3375 5925);
DISPLAY 0.510638 (-3375 5925);
PAINT WHITE (-3375 5925);
DISPLAY INVISIBLE (-3375 5925);
FORCEPROP 1 LAST LOCATION R45
J 0
(-3650 5825);
DISPLAY 0.702128 (-3650 5825);
PAINT YELLOW (-3650 5825);
FORCEPROP 0 LAST $SEC 1
J 0
(-3675 5875);
DISPLAY INVISIBLE (-3675 5875);
FORCEPROP 0 LAST CDS_SEC 1
J 0
(-3675 5875);
DISPLAY INVISIBLE (-3675 5875);
FORCEPROP 1 LASTPIN (-3425 5825) $PN 1
J 0
(-3413 5837);
DISPLAY 0.808511 (-3413 5837);
PAINT WHITE (-3413 5837);
DISPLAY INVISIBLE (-3413 5837);
FORCEPROP 1 LASTPIN (-3225 5825) $PN 2
J 0
(-3263 5837);
DISPLAY 0.808511 (-3263 5837);
PAINT WHITE (-3263 5837);
DISPLAY INVISIBLE (-3263 5837);
FORCEADD Q_RES..1
(-3300 4625);
FORCEPROP 1 LAST VALUE 4.7K
J 0
(-3125 4625);
DISPLAY 0.510638 (-3125 4625);
PAINT SKYBLUE (-3125 4625);
FORCEPROP 1 LAST MATERIAL CHIP
J 0
(-2950 4625);
DISPLAY 0.510638 (-2950 4625);
PAINT SKYBLUE (-2950 4625);
FORCEPROP 2 LAST CDS_LIB pure_quanta
J 0
(-3300 4625);
DISPLAY INVISIBLE (-3300 4625);
FORCEPROP 1 LAST TOLERANCE 1%
J 0
(-3300 4525);
DISPLAY 0.510638 (-3300 4525);
PAINT SKYBLUE (-3300 4525);
DISPLAY INVISIBLE (-3300 4525);
FORCEPROP 1 LAST PATH I179
J 0
(-3350 4775);
DISPLAY 0.978723 (-3350 4775);
PAINT WHITE (-3350 4775);
DISPLAY INVISIBLE (-3350 4775);
FORCEPROP 1 LAST WATTAGE 1/16W
J 2
(-3325 4475);
DISPLAY 0.510638 (-3325 4475);
PAINT SKYBLUE (-3325 4475);
DISPLAY INVISIBLE (-3325 4475);
FORCEPROP 1 LAST PACK_TYPE 0402LF
J 0
(-3050 4475);
DISPLAY 0.510638 (-3050 4475);
PAINT SKYBLUE (-3050 4475);
DISPLAY INVISIBLE (-3050 4475);
FORCEPROP 1 LAST PART_NUMBER CS24702FB06
J 0
(-3350 4725);
DISPLAY 0.510638 (-3350 4725);
PAINT WHITE (-3350 4725);
DISPLAY INVISIBLE (-3350 4725);
FORCEPROP 1 LAST LOCATION R68
J 0
(-3625 4625);
DISPLAY 0.702128 (-3625 4625);
PAINT YELLOW (-3625 4625);
FORCEPROP 0 LAST $SEC 1
J 0
(-3650 4675);
DISPLAY INVISIBLE (-3650 4675);
FORCEPROP 0 LAST CDS_SEC 1
J 0
(-3650 4675);
DISPLAY INVISIBLE (-3650 4675);
FORCEPROP 1 LASTPIN (-3400 4625) $PN 1
J 0
(-3388 4637);
DISPLAY 0.808511 (-3388 4637);
PAINT WHITE (-3388 4637);
DISPLAY INVISIBLE (-3388 4637);
FORCEPROP 1 LASTPIN (-3200 4625) $PN 2
J 0
(-3238 4637);
DISPLAY 0.808511 (-3238 4637);
PAINT WHITE (-3238 4637);
DISPLAY INVISIBLE (-3238 4637);
FORCEADD Q_RES..1
(-200 3950);
FORCEPROP 1 LAST PACK_TYPE 0402LF
J 0
(50 3800);
DISPLAY 0.510638 (50 3800);
PAINT SKYBLUE (50 3800);
FORCEPROP 1 LAST PART_NUMBER CS41002FB09
J 0
(-250 4050);
DISPLAY 0.510638 (-250 4050);
PAINT WHITE (-250 4050);
FORCEPROP 1 LAST TOLERANCE 1%
J 0
(-200 3850);
DISPLAY 0.510638 (-200 3850);
PAINT SKYBLUE (-200 3850);
FORCEPROP 1 LAST VALUE 100K
J 2
(-225 3850);
DISPLAY 0.510638 (-225 3850);
PAINT SKYBLUE (-225 3850);
FORCEPROP 1 LAST WATTAGE 1/16W
J 2
(-225 3800);
DISPLAY 0.510638 (-225 3800);
PAINT SKYBLUE (-225 3800);
FORCEPROP 1 LAST MATERIAL CHIP
J 0
(-200 3800);
DISPLAY 0.510638 (-200 3800);
PAINT SKYBLUE (-200 3800);
FORCEPROP 2 LAST CDS_LIB pure_quanta
J 0
(-200 3950);
DISPLAY INVISIBLE (-200 3950);
FORCEPROP 1 LAST PATH I181
J 0
(-250 4100);
DISPLAY 0.978723 (-250 4100);
PAINT WHITE (-250 4100);
DISPLAY INVISIBLE (-250 4100);
FORCEPROP 1 LAST LOCATION R66
J 0
(-575 3950);
DISPLAY 0.702128 (-575 3950);
PAINT YELLOW (-575 3950);
FORCEPROP 0 LAST $SEC 1
J 0
(-250 4075);
DISPLAY 0.680851 (-250 4075);
PAINT MONO (-250 4075);
DISPLAY INVISIBLE (-250 4075);
FORCEPROP 0 LAST CDS_SEC 1
J 0
(-550 4000);
DISPLAY INVISIBLE (-550 4000);
FORCEPROP 1 LASTPIN (-300 3950) $PN 1
J 0
(-288 3962);
DISPLAY 0.808511 (-288 3962);
PAINT WHITE (-288 3962);
DISPLAY INVISIBLE (-288 3962);
FORCEPROP 1 LASTPIN (-100 3950) $PN 2
J 0
(-138 3962);
DISPLAY 0.808511 (-138 3962);
PAINT WHITE (-138 3962);
DISPLAY INVISIBLE (-138 3962);
FORCEADD OFFPAGE..2
(-1675 6975);
FORCEPROP 2 LAST $XR0 10 
J 0
(-1486 6975);
DISPLAY 0.638298 (-1486 6975);
PAINT MONO (-1486 6975);
FORCEPROP 2 LAST $XR1 12 
J 0
(-1396 6975);
DISPLAY 0.638298 (-1396 6975);
PAINT MONO (-1396 6975);
FORCEPROP 2 LAST $XR2 28 
J 0
(-1306 6975);
DISPLAY 0.638298 (-1306 6975);
PAINT MONO (-1306 6975);
FORCEPROP 2 LAST $XR3 34 
J 0
(-1216 6975);
DISPLAY 0.638298 (-1216 6975);
PAINT MONO (-1216 6975);
FORCEPROP 2 LAST $XR4 46 
J 0
(-1126 6975);
DISPLAY 0.638298 (-1126 6975);
PAINT MONO (-1126 6975);
FORCEPROP 1 LAST OFFPAGE TRUE
J 0
(-1350 6850);
DISPLAY 0.872340 (-1350 6850);
PAINT GREEN (-1350 6850);
DISPLAY INVISIBLE (-1350 6850);
FORCEPROP 1 LAST COMMENT_BODY TRUE
J 0
(-1720 6880);
DISPLAY 0.872340 (-1720 6880);
PAINT PEACH (-1720 6880);
DISPLAY INVISIBLE (-1720 6880);
FORCEPROP 2 LAST PATH I193
J 0
(-1500 7050);
DISPLAY 1.021277 (-1500 7050);
DISPLAY INVISIBLE (-1500 7050);
FORCEPROP 2 LAST CDS_LIB standard
J 0
(-1675 6975);
DISPLAY INVISIBLE (-1675 6975);
FORCEADD Q_RES..1
(-3375 6975);
FORCEPROP 1 LAST VALUE 4.7K
J 0
(-3200 6975);
DISPLAY 0.510638 (-3200 6975);
PAINT SKYBLUE (-3200 6975);
FORCEPROP 1 LAST MATERIAL EMPTY
J 0
(-3025 6975);
DISPLAY 0.510638 (-3025 6975);
PAINT RED (-3025 6975);
FORCEPROP 1 LAST PART_NUMBER CS24702FB06
J 0
(-3425 7075);
DISPLAY 0.510638 (-3425 7075);
PAINT WHITE (-3425 7075);
DISPLAY INVISIBLE (-3425 7075);
FORCEPROP 1 LAST PACK_TYPE 0402LF
J 0
(-3125 6825);
DISPLAY 0.510638 (-3125 6825);
PAINT SKYBLUE (-3125 6825);
DISPLAY INVISIBLE (-3125 6825);
FORCEPROP 1 LAST WATTAGE 1/16W
J 2
(-3400 6825);
DISPLAY 0.510638 (-3400 6825);
PAINT SKYBLUE (-3400 6825);
DISPLAY INVISIBLE (-3400 6825);
FORCEPROP 1 LAST TOLERANCE 1%
J 0
(-3375 6875);
DISPLAY 0.510638 (-3375 6875);
PAINT SKYBLUE (-3375 6875);
DISPLAY INVISIBLE (-3375 6875);
FORCEPROP 1 LAST PATH I194
J 0
(-3425 7125);
DISPLAY 0.978723 (-3425 7125);
PAINT WHITE (-3425 7125);
DISPLAY INVISIBLE (-3425 7125);
FORCEPROP 2 LAST CDS_LIB pure_quanta
J 0
(-3375 6975);
DISPLAY INVISIBLE (-3375 6975);
FORCEPROP 1 LAST LOCATION R34
J 0
(-3700 6975);
DISPLAY 0.702128 (-3700 6975);
PAINT YELLOW (-3700 6975);
FORCEPROP 0 LAST $SEC 1
J 0
(-3725 7025);
DISPLAY INVISIBLE (-3725 7025);
FORCEPROP 0 LAST CDS_SEC 1
J 0
(-3725 7025);
DISPLAY INVISIBLE (-3725 7025);
FORCEPROP 1 LASTPIN (-3475 6975) $PN 1
J 0
(-3463 6987);
DISPLAY 0.808511 (-3463 6987);
PAINT WHITE (-3463 6987);
DISPLAY INVISIBLE (-3463 6987);
FORCEPROP 1 LASTPIN (-3275 6975) $PN 2
J 0
(-3313 6987);
DISPLAY 0.808511 (-3313 6987);
PAINT WHITE (-3313 6987);
DISPLAY INVISIBLE (-3313 6987);
FORCEADD UNIVERSAL_GND..1
(-825 2925);
FORCEPROP 3 LASTPIN (-825 2975) SIG_NAME GND\g
J 0
(-815 2985);
DISPLAY 0.659574 (-815 2985);
PAINT MONO (-815 2985);
DISPLAY INVISIBLE (-815 2985);
FORCEPROP 2 LAST CDS_LIB logical_power
J 0
(-825 2925);
DISPLAY INVISIBLE (-825 2925);
FORCEPROP 1 LAST HDL_POWER GND
J 1
(-800 2850);
DISPLAY 0.702128 (-800 2850);
PAINT GREEN (-800 2850);
DISPLAY INVISIBLE (-800 2850);
FORCEPROP 1 LAST PATH I2
J 0
(-750 2925);
DISPLAY 0.872340 (-750 2925);
PAINT AQUA (-750 2925);
DISPLAY INVISIBLE (-750 2925);
FORCEADD Q_RES..1
(-3325 5625);
FORCEPROP 1 LAST VALUE 4.7K
J 0
(-3150 5625);
DISPLAY 0.510638 (-3150 5625);
PAINT SKYBLUE (-3150 5625);
FORCEPROP 1 LAST MATERIAL CHIP
J 0
(-2975 5625);
DISPLAY 0.510638 (-2975 5625);
PAINT SKYBLUE (-2975 5625);
FORCEPROP 2 LAST CDS_LIB pure_quanta
J 0
(-3325 5625);
DISPLAY INVISIBLE (-3325 5625);
FORCEPROP 1 LAST TOLERANCE 1%
J 0
(-3325 5525);
DISPLAY 0.510638 (-3325 5525);
PAINT SKYBLUE (-3325 5525);
DISPLAY INVISIBLE (-3325 5525);
FORCEPROP 1 LAST PATH I212
J 0
(-3375 5775);
DISPLAY 0.978723 (-3375 5775);
PAINT WHITE (-3375 5775);
DISPLAY INVISIBLE (-3375 5775);
FORCEPROP 1 LAST WATTAGE 1/16W
J 2
(-3350 5475);
DISPLAY 0.510638 (-3350 5475);
PAINT SKYBLUE (-3350 5475);
DISPLAY INVISIBLE (-3350 5475);
FORCEPROP 1 LAST PACK_TYPE 0402LF
J 0
(-3075 5475);
DISPLAY 0.510638 (-3075 5475);
PAINT SKYBLUE (-3075 5475);
DISPLAY INVISIBLE (-3075 5475);
FORCEPROP 1 LAST PART_NUMBER CS24702FB06
J 0
(-3375 5725);
DISPLAY 0.510638 (-3375 5725);
PAINT WHITE (-3375 5725);
DISPLAY INVISIBLE (-3375 5725);
FORCEPROP 1 LAST LOCATION R163
J 0
(-3650 5625);
DISPLAY 0.702128 (-3650 5625);
PAINT YELLOW (-3650 5625);
FORCEPROP 0 LAST $SEC 1
J 0
(-3675 5675);
DISPLAY INVISIBLE (-3675 5675);
FORCEPROP 0 LAST CDS_SEC 1
J 0
(-3675 5675);
DISPLAY INVISIBLE (-3675 5675);
FORCEPROP 1 LASTPIN (-3425 5625) $PN 1
J 0
(-3413 5637);
DISPLAY 0.808511 (-3413 5637);
PAINT WHITE (-3413 5637);
DISPLAY INVISIBLE (-3413 5637);
FORCEPROP 1 LASTPIN (-3225 5625) $PN 2
J 0
(-3263 5637);
DISPLAY 0.808511 (-3263 5637);
PAINT WHITE (-3263 5637);
DISPLAY INVISIBLE (-3263 5637);
FORCEADD OFFPAGE..2
(-1675 5625);
FORCEPROP 2 LAST $XR2 28 
J 0
(-1306 5625);
DISPLAY 0.638298 (-1306 5625);
PAINT MONO (-1306 5625);
FORCEPROP 2 LAST $XR0 34 
J 0
(-1486 5625);
DISPLAY 0.638298 (-1486 5625);
PAINT MONO (-1486 5625);
FORCEPROP 2 LAST $XR1 13 
J 0
(-1396 5625);
DISPLAY 0.638298 (-1396 5625);
PAINT MONO (-1396 5625);
FORCEPROP 2 LAST CDS_LIB standard
J 0
(-1675 5625);
DISPLAY INVISIBLE (-1675 5625);
FORCEPROP 1 LAST OFFPAGE TRUE
J 0
(-1350 5500);
DISPLAY 0.872340 (-1350 5500);
PAINT GREEN (-1350 5500);
DISPLAY INVISIBLE (-1350 5500);
FORCEPROP 1 LAST COMMENT_BODY TRUE
J 0
(-1720 5530);
DISPLAY 0.872340 (-1720 5530);
PAINT PEACH (-1720 5530);
DISPLAY INVISIBLE (-1720 5530);
FORCEPROP 2 LAST PATH I213
J 0
(-1500 5700);
DISPLAY 1.021277 (-1500 5700);
DISPLAY INVISIBLE (-1500 5700);
FORCEADD Q_RES..1
(-3325 5425);
FORCEPROP 1 LAST VALUE 4.7K
J 0
(-3150 5425);
DISPLAY 0.510638 (-3150 5425);
PAINT SKYBLUE (-3150 5425);
FORCEPROP 1 LAST MATERIAL CHIP
J 0
(-2975 5425);
DISPLAY 0.510638 (-2975 5425);
PAINT SKYBLUE (-2975 5425);
FORCEPROP 2 LAST CDS_LIB pure_quanta
J 0
(-3325 5425);
DISPLAY INVISIBLE (-3325 5425);
FORCEPROP 1 LAST TOLERANCE 1%
J 0
(-3325 5325);
DISPLAY 0.510638 (-3325 5325);
PAINT SKYBLUE (-3325 5325);
DISPLAY INVISIBLE (-3325 5325);
FORCEPROP 1 LAST PATH I214
J 0
(-3375 5575);
DISPLAY 0.978723 (-3375 5575);
PAINT WHITE (-3375 5575);
DISPLAY INVISIBLE (-3375 5575);
FORCEPROP 1 LAST WATTAGE 1/16W
J 2
(-3350 5275);
DISPLAY 0.510638 (-3350 5275);
PAINT SKYBLUE (-3350 5275);
DISPLAY INVISIBLE (-3350 5275);
FORCEPROP 1 LAST PACK_TYPE 0402LF
J 0
(-3075 5275);
DISPLAY 0.510638 (-3075 5275);
PAINT SKYBLUE (-3075 5275);
DISPLAY INVISIBLE (-3075 5275);
FORCEPROP 1 LAST PART_NUMBER CS24702FB06
J 0
(-3375 5525);
DISPLAY 0.510638 (-3375 5525);
PAINT WHITE (-3375 5525);
DISPLAY INVISIBLE (-3375 5525);
FORCEPROP 1 LAST LOCATION R101
J 0
(-3650 5425);
DISPLAY 0.702128 (-3650 5425);
PAINT YELLOW (-3650 5425);
FORCEPROP 0 LAST $SEC 1
J 0
(-3675 5475);
DISPLAY INVISIBLE (-3675 5475);
FORCEPROP 0 LAST CDS_SEC 1
J 0
(-3675 5475);
DISPLAY INVISIBLE (-3675 5475);
FORCEPROP 1 LASTPIN (-3425 5425) $PN 1
J 0
(-3413 5437);
DISPLAY 0.808511 (-3413 5437);
PAINT WHITE (-3413 5437);
DISPLAY INVISIBLE (-3413 5437);
FORCEPROP 1 LASTPIN (-3225 5425) $PN 2
J 0
(-3263 5437);
DISPLAY 0.808511 (-3263 5437);
PAINT WHITE (-3263 5437);
DISPLAY INVISIBLE (-3263 5437);
FORCEADD OFFPAGE..2
(-1675 5425);
FORCEPROP 2 LAST $XR0 10 
J 0
(-1486 5425);
DISPLAY 0.638298 (-1486 5425);
PAINT MONO (-1486 5425);
FORCEPROP 2 LAST $XR1 13 
J 0
(-1396 5425);
DISPLAY 0.638298 (-1396 5425);
PAINT MONO (-1396 5425);
FORCEPROP 2 LAST CDS_LIB standard
J 0
(-1675 5425);
DISPLAY INVISIBLE (-1675 5425);
FORCEPROP 1 LAST OFFPAGE TRUE
J 0
(-1350 5300);
DISPLAY 0.872340 (-1350 5300);
PAINT GREEN (-1350 5300);
DISPLAY INVISIBLE (-1350 5300);
FORCEPROP 1 LAST COMMENT_BODY TRUE
J 0
(-1720 5330);
DISPLAY 0.872340 (-1720 5330);
PAINT PEACH (-1720 5330);
DISPLAY INVISIBLE (-1720 5330);
FORCEPROP 2 LAST PATH I215
J 0
(-1500 5500);
DISPLAY 1.021277 (-1500 5500);
DISPLAY INVISIBLE (-1500 5500);
FORCEADD OFFPAGE..2
(-1675 5225);
FORCEPROP 2 LAST $XR0 13 
J 0
(-1486 5225);
DISPLAY 0.638298 (-1486 5225);
PAINT MONO (-1486 5225);
FORCEPROP 2 LAST $XR1 10 
J 0
(-1396 5225);
DISPLAY 0.638298 (-1396 5225);
PAINT MONO (-1396 5225);
FORCEPROP 2 LAST CDS_LIB standard
J 0
(-1675 5225);
DISPLAY INVISIBLE (-1675 5225);
FORCEPROP 1 LAST OFFPAGE TRUE
J 0
(-1350 5100);
DISPLAY 0.872340 (-1350 5100);
PAINT GREEN (-1350 5100);
DISPLAY INVISIBLE (-1350 5100);
FORCEPROP 1 LAST COMMENT_BODY TRUE
J 0
(-1720 5130);
DISPLAY 0.872340 (-1720 5130);
PAINT PEACH (-1720 5130);
DISPLAY INVISIBLE (-1720 5130);
FORCEPROP 2 LAST PATH I216
J 0
(-1500 5300);
DISPLAY 1.021277 (-1500 5300);
DISPLAY INVISIBLE (-1500 5300);
FORCEADD OFFPAGE..2
(-1675 5025);
FORCEPROP 2 LAST $XR0 10 
J 0
(-1486 5025);
DISPLAY 0.638298 (-1486 5025);
PAINT MONO (-1486 5025);
FORCEPROP 2 LAST $XR1 13 
J 0
(-1396 5025);
DISPLAY 0.638298 (-1396 5025);
PAINT MONO (-1396 5025);
FORCEPROP 2 LAST CDS_LIB standard
J 0
(-1675 5025);
DISPLAY INVISIBLE (-1675 5025);
FORCEPROP 1 LAST OFFPAGE TRUE
J 0
(-1350 4900);
DISPLAY 0.872340 (-1350 4900);
PAINT GREEN (-1350 4900);
DISPLAY INVISIBLE (-1350 4900);
FORCEPROP 1 LAST COMMENT_BODY TRUE
J 0
(-1720 4930);
DISPLAY 0.872340 (-1720 4930);
PAINT PEACH (-1720 4930);
DISPLAY INVISIBLE (-1720 4930);
FORCEPROP 2 LAST PATH I217
J 0
(-1500 5100);
DISPLAY 1.021277 (-1500 5100);
DISPLAY INVISIBLE (-1500 5100);
FORCEADD Q_RES..1
(-3325 5025);
FORCEPROP 1 LAST VALUE 4.7K
J 0
(-3150 5025);
DISPLAY 0.510638 (-3150 5025);
PAINT SKYBLUE (-3150 5025);
FORCEPROP 1 LAST MATERIAL CHIP
J 0
(-2975 5025);
DISPLAY 0.510638 (-2975 5025);
PAINT SKYBLUE (-2975 5025);
FORCEPROP 2 LAST CDS_LIB pure_quanta
J 0
(-3325 5025);
DISPLAY INVISIBLE (-3325 5025);
FORCEPROP 1 LAST TOLERANCE 1%
J 0
(-3325 4925);
DISPLAY 0.510638 (-3325 4925);
PAINT SKYBLUE (-3325 4925);
DISPLAY INVISIBLE (-3325 4925);
FORCEPROP 1 LAST PATH I218
J 0
(-3375 5175);
DISPLAY 0.978723 (-3375 5175);
PAINT WHITE (-3375 5175);
DISPLAY INVISIBLE (-3375 5175);
FORCEPROP 1 LAST WATTAGE 1/16W
J 2
(-3350 4875);
DISPLAY 0.510638 (-3350 4875);
PAINT SKYBLUE (-3350 4875);
DISPLAY INVISIBLE (-3350 4875);
FORCEPROP 1 LAST PACK_TYPE 0402LF
J 0
(-3075 4875);
DISPLAY 0.510638 (-3075 4875);
PAINT SKYBLUE (-3075 4875);
DISPLAY INVISIBLE (-3075 4875);
FORCEPROP 1 LAST PART_NUMBER CS24702FB06
J 0
(-3375 5125);
DISPLAY 0.510638 (-3375 5125);
PAINT WHITE (-3375 5125);
DISPLAY INVISIBLE (-3375 5125);
FORCEPROP 1 LAST LOCATION R161
J 0
(-3650 5025);
DISPLAY 0.702128 (-3650 5025);
PAINT YELLOW (-3650 5025);
FORCEPROP 0 LAST $SEC 1
J 0
(-3675 5075);
DISPLAY INVISIBLE (-3675 5075);
FORCEPROP 0 LAST CDS_SEC 1
J 0
(-3675 5075);
DISPLAY INVISIBLE (-3675 5075);
FORCEPROP 1 LASTPIN (-3425 5025) $PN 1
J 0
(-3413 5037);
DISPLAY 0.808511 (-3413 5037);
PAINT WHITE (-3413 5037);
DISPLAY INVISIBLE (-3413 5037);
FORCEPROP 1 LASTPIN (-3225 5025) $PN 2
J 0
(-3263 5037);
DISPLAY 0.808511 (-3263 5037);
PAINT WHITE (-3263 5037);
DISPLAY INVISIBLE (-3263 5037);
FORCEADD Q_RES..1
(-3325 5225);
FORCEPROP 1 LAST VALUE 4.7K
J 0
(-3150 5225);
DISPLAY 0.510638 (-3150 5225);
PAINT SKYBLUE (-3150 5225);
FORCEPROP 1 LAST MATERIAL CHIP
J 0
(-2975 5225);
DISPLAY 0.510638 (-2975 5225);
PAINT SKYBLUE (-2975 5225);
FORCEPROP 2 LAST CDS_LIB pure_quanta
J 0
(-3325 5225);
DISPLAY INVISIBLE (-3325 5225);
FORCEPROP 1 LAST TOLERANCE 1%
J 0
(-3325 5125);
DISPLAY 0.510638 (-3325 5125);
PAINT SKYBLUE (-3325 5125);
DISPLAY INVISIBLE (-3325 5125);
FORCEPROP 1 LAST PATH I219
J 0
(-3375 5375);
DISPLAY 0.978723 (-3375 5375);
PAINT WHITE (-3375 5375);
DISPLAY INVISIBLE (-3375 5375);
FORCEPROP 1 LAST WATTAGE 1/16W
J 2
(-3350 5075);
DISPLAY 0.510638 (-3350 5075);
PAINT SKYBLUE (-3350 5075);
DISPLAY INVISIBLE (-3350 5075);
FORCEPROP 1 LAST PACK_TYPE 0402LF
J 0
(-3075 5075);
DISPLAY 0.510638 (-3075 5075);
PAINT SKYBLUE (-3075 5075);
DISPLAY INVISIBLE (-3075 5075);
FORCEPROP 1 LAST PART_NUMBER CS24702FB06
J 0
(-3375 5325);
DISPLAY 0.510638 (-3375 5325);
PAINT WHITE (-3375 5325);
DISPLAY INVISIBLE (-3375 5325);
FORCEPROP 1 LAST LOCATION R103
J 0
(-3650 5225);
DISPLAY 0.702128 (-3650 5225);
PAINT YELLOW (-3650 5225);
FORCEPROP 0 LAST $SEC 1
J 0
(-3675 5275);
DISPLAY INVISIBLE (-3675 5275);
FORCEPROP 0 LAST CDS_SEC 1
J 0
(-3675 5275);
DISPLAY INVISIBLE (-3675 5275);
FORCEPROP 1 LASTPIN (-3425 5225) $PN 1
J 0
(-3413 5237);
DISPLAY 0.808511 (-3413 5237);
PAINT WHITE (-3413 5237);
DISPLAY INVISIBLE (-3413 5237);
FORCEPROP 1 LASTPIN (-3225 5225) $PN 2
J 0
(-3263 5237);
DISPLAY 0.808511 (-3263 5237);
PAINT WHITE (-3263 5237);
DISPLAY INVISIBLE (-3263 5237);
FORCEADD OFFPAGE..2
(-1675 6225);
FORCEPROP 2 LAST $XR1 17 
J 0
(-1396 6225);
DISPLAY 0.638298 (-1396 6225);
PAINT MONO (-1396 6225);
FORCEPROP 2 LAST $XR0 10 
J 0
(-1486 6225);
DISPLAY 0.638298 (-1486 6225);
PAINT MONO (-1486 6225);
FORCEPROP 2 LAST $XR2 27 
J 0
(-1306 6225);
DISPLAY 0.638298 (-1306 6225);
PAINT MONO (-1306 6225);
FORCEPROP 2 LAST CDS_LIB standard
J 0
(-1675 6225);
DISPLAY INVISIBLE (-1675 6225);
FORCEPROP 1 LAST OFFPAGE TRUE
J 0
(-1350 6100);
DISPLAY 0.872340 (-1350 6100);
PAINT GREEN (-1350 6100);
DISPLAY INVISIBLE (-1350 6100);
FORCEPROP 1 LAST COMMENT_BODY TRUE
J 0
(-1720 6130);
DISPLAY 0.872340 (-1720 6130);
PAINT PEACH (-1720 6130);
DISPLAY INVISIBLE (-1720 6130);
FORCEPROP 2 LAST PATH I222
J 0
(-1425 6275);
DISPLAY 1.021277 (-1425 6275);
DISPLAY INVISIBLE (-1425 6275);
FORCEADD Q_RES..1
(-3325 6225);
FORCEPROP 1 LAST VALUE 10K
J 0
(-3150 6225);
DISPLAY 0.510638 (-3150 6225);
PAINT SKYBLUE (-3150 6225);
FORCEPROP 1 LAST MATERIAL EMPTY
J 0
(-2975 6225);
DISPLAY 0.510638 (-2975 6225);
PAINT RED (-2975 6225);
FORCEPROP 2 LAST CDS_LIB pure_quanta
J 0
(-3325 6225);
DISPLAY INVISIBLE (-3325 6225);
FORCEPROP 1 LAST TOLERANCE 1%
J 0
(-3325 6125);
DISPLAY 0.510638 (-3325 6125);
PAINT SKYBLUE (-3325 6125);
DISPLAY INVISIBLE (-3325 6125);
FORCEPROP 1 LAST PATH I225
J 0
(-3375 6375);
DISPLAY 0.978723 (-3375 6375);
PAINT WHITE (-3375 6375);
DISPLAY INVISIBLE (-3375 6375);
FORCEPROP 1 LAST WATTAGE 1/16W
J 2
(-3350 6075);
DISPLAY 0.510638 (-3350 6075);
PAINT SKYBLUE (-3350 6075);
DISPLAY INVISIBLE (-3350 6075);
FORCEPROP 1 LAST PACK_TYPE 0402LF
J 0
(-3075 6075);
DISPLAY 0.510638 (-3075 6075);
PAINT SKYBLUE (-3075 6075);
DISPLAY INVISIBLE (-3075 6075);
FORCEPROP 1 LAST PART_NUMBER CS31002FB08
J 0
(-3375 6325);
DISPLAY 0.510638 (-3375 6325);
PAINT WHITE (-3375 6325);
DISPLAY INVISIBLE (-3375 6325);
FORCEPROP 1 LAST LOCATION R41
J 0
(-3650 6225);
DISPLAY 0.702128 (-3650 6225);
PAINT YELLOW (-3650 6225);
FORCEPROP 0 LAST $SEC 1
J 0
(-3650 6275);
DISPLAY 0.680851 (-3650 6275);
PAINT MONO (-3650 6275);
DISPLAY INVISIBLE (-3650 6275);
FORCEPROP 0 LAST CDS_SEC 1
J 0
(-3650 6275);
DISPLAY 1.021277 (-3650 6275);
DISPLAY INVISIBLE (-3650 6275);
FORCEPROP 1 LASTPIN (-3425 6225) $PN 1
J 0
(-3413 6237);
DISPLAY 0.808511 (-3413 6237);
PAINT WHITE (-3413 6237);
DISPLAY INVISIBLE (-3413 6237);
FORCEPROP 1 LASTPIN (-3225 6225) $PN 2
J 0
(-3263 6237);
DISPLAY 0.808511 (-3263 6237);
PAINT WHITE (-3263 6237);
DISPLAY INVISIBLE (-3263 6237);
FORCEADD OFFPAGE..2
(-1675 4825);
FORCEPROP 2 LAST $XR0 13 
J 0
(-1486 4825);
DISPLAY 0.638298 (-1486 4825);
PAINT MONO (-1486 4825);
FORCEPROP 2 LAST $XR1 10 
J 0
(-1396 4825);
DISPLAY 0.638298 (-1396 4825);
PAINT MONO (-1396 4825);
FORCEPROP 2 LAST $XR2 35 
J 0
(-1306 4825);
DISPLAY 0.638298 (-1306 4825);
PAINT MONO (-1306 4825);
FORCEPROP 2 LAST CDS_LIB standard
J 0
(-1675 4825);
DISPLAY INVISIBLE (-1675 4825);
FORCEPROP 1 LAST OFFPAGE TRUE
J 0
(-1350 4700);
DISPLAY 0.872340 (-1350 4700);
PAINT GREEN (-1350 4700);
DISPLAY INVISIBLE (-1350 4700);
FORCEPROP 1 LAST COMMENT_BODY TRUE
J 0
(-1720 4730);
DISPLAY 0.872340 (-1720 4730);
PAINT PEACH (-1720 4730);
DISPLAY INVISIBLE (-1720 4730);
FORCEPROP 2 LAST PATH I226
J 0
(-1300 4875);
DISPLAY 1.021277 (-1300 4875);
DISPLAY INVISIBLE (-1300 4875);
FORCEADD Q_RES..1
(-3300 4825);
FORCEPROP 1 LAST VALUE 4.7K
J 0
(-3125 4825);
DISPLAY 0.510638 (-3125 4825);
PAINT SKYBLUE (-3125 4825);
FORCEPROP 1 LAST MATERIAL CHIP
J 0
(-2950 4825);
DISPLAY 0.510638 (-2950 4825);
PAINT SKYBLUE (-2950 4825);
FORCEPROP 2 LAST CDS_LIB pure_quanta
J 0
(-3300 4825);
DISPLAY INVISIBLE (-3300 4825);
FORCEPROP 1 LAST TOLERANCE 1%
J 0
(-3300 4725);
DISPLAY 0.510638 (-3300 4725);
PAINT SKYBLUE (-3300 4725);
DISPLAY INVISIBLE (-3300 4725);
FORCEPROP 1 LAST PATH I227
J 0
(-3350 4975);
DISPLAY 0.978723 (-3350 4975);
PAINT WHITE (-3350 4975);
DISPLAY INVISIBLE (-3350 4975);
FORCEPROP 1 LAST WATTAGE 1/16W
J 2
(-3325 4675);
DISPLAY 0.510638 (-3325 4675);
PAINT SKYBLUE (-3325 4675);
DISPLAY INVISIBLE (-3325 4675);
FORCEPROP 1 LAST PACK_TYPE 0402LF
J 0
(-3050 4675);
DISPLAY 0.510638 (-3050 4675);
PAINT SKYBLUE (-3050 4675);
DISPLAY INVISIBLE (-3050 4675);
FORCEPROP 1 LAST PART_NUMBER CS24702FB06
J 0
(-3350 4925);
DISPLAY 0.510638 (-3350 4925);
PAINT WHITE (-3350 4925);
DISPLAY INVISIBLE (-3350 4925);
FORCEPROP 1 LAST LOCATION R69
J 0
(-3625 4825);
DISPLAY 0.702128 (-3625 4825);
PAINT YELLOW (-3625 4825);
FORCEPROP 0 LAST $SEC 1
J 0
(-3650 4875);
DISPLAY INVISIBLE (-3650 4875);
FORCEPROP 0 LAST CDS_SEC 1
J 0
(-3650 4875);
DISPLAY INVISIBLE (-3650 4875);
FORCEPROP 1 LASTPIN (-3400 4825) $PN 1
J 0
(-3388 4837);
DISPLAY 0.808511 (-3388 4837);
PAINT WHITE (-3388 4837);
DISPLAY INVISIBLE (-3388 4837);
FORCEPROP 1 LASTPIN (-3200 4825) $PN 2
J 0
(-3238 4837);
DISPLAY 0.808511 (-3238 4837);
PAINT WHITE (-3238 4837);
DISPLAY INVISIBLE (-3238 4837);
FORCEADD OFFPAGE..2
(4425 5750);
FORCEPROP 2 LAST $XR1 10 
J 0
(4704 5750);
DISPLAY 0.638298 (4704 5750);
PAINT MONO (4704 5750);
FORCEPROP 2 LAST $XR0 12 
J 0
(4614 5750);
DISPLAY 0.638298 (4614 5750);
PAINT MONO (4614 5750);
FORCEPROP 2 LAST CDS_LIB standard
J 0
(4425 5750);
DISPLAY INVISIBLE (4425 5750);
FORCEPROP 1 LAST OFFPAGE TRUE
J 0
(4750 5625);
DISPLAY 0.872340 (4750 5625);
PAINT GREEN (4750 5625);
DISPLAY INVISIBLE (4750 5625);
FORCEPROP 1 LAST COMMENT_BODY TRUE
J 0
(4380 5655);
DISPLAY 0.872340 (4380 5655);
PAINT PEACH (4380 5655);
DISPLAY INVISIBLE (4380 5655);
FORCEPROP 2 LAST PATH I228
J 0
(4800 5800);
DISPLAY 1.021277 (4800 5800);
DISPLAY INVISIBLE (4800 5800);
FORCEADD OFFPAGE..2
(4425 6125);
FORCEPROP 2 LAST $XR0 34 
J 0
(4614 6125);
DISPLAY 0.638298 (4614 6125);
PAINT MONO (4614 6125);
FORCEPROP 2 LAST $XR1 10 
J 0
(4704 6125);
DISPLAY 0.638298 (4704 6125);
PAINT MONO (4704 6125);
FORCEPROP 2 LAST CDS_LIB standard
J 0
(4425 6125);
DISPLAY INVISIBLE (4425 6125);
FORCEPROP 1 LAST OFFPAGE TRUE
J 0
(4750 6000);
DISPLAY 0.872340 (4750 6000);
PAINT GREEN (4750 6000);
DISPLAY INVISIBLE (4750 6000);
FORCEPROP 1 LAST COMMENT_BODY TRUE
J 0
(4380 6030);
DISPLAY 0.872340 (4380 6030);
PAINT PEACH (4380 6030);
DISPLAY INVISIBLE (4380 6030);
FORCEPROP 2 LAST PATH I229
J 0
(4800 6175);
DISPLAY 1.021277 (4800 6175);
DISPLAY INVISIBLE (4800 6175);
FORCEADD Q_RES..1
(2450 5750);
FORCEPROP 1 LAST TOLERANCE 1%
J 0
(2400 5675);
DISPLAY 0.510638 (2400 5675);
PAINT SKYBLUE (2400 5675);
FORCEPROP 1 LAST PACK_TYPE 0402LF
J 0
(2500 5675);
DISPLAY 0.510638 (2500 5675);
PAINT SKYBLUE (2500 5675);
FORCEPROP 1 LAST MATERIAL CHIP
J 0
(2875 5750);
DISPLAY 0.510638 (2875 5750);
PAINT SKYBLUE (2875 5750);
FORCEPROP 1 LAST VALUE 2K
J 2
(2675 5750);
DISPLAY 0.510638 (2675 5750);
PAINT SKYBLUE (2675 5750);
FORCEPROP 1 LAST WATTAGE 1/16W
J 0
(2225 5675);
DISPLAY 0.510638 (2225 5675);
PAINT SKYBLUE (2225 5675);
FORCEPROP 2 LAST CDS_LIB pure_quanta
J 0
(2450 5750);
DISPLAY INVISIBLE (2450 5750);
FORCEPROP 1 LAST PATH I230
J 0
(2400 5900);
DISPLAY 0.978723 (2400 5900);
PAINT WHITE (2400 5900);
DISPLAY INVISIBLE (2400 5900);
FORCEPROP 1 LAST PART_NUMBER CS22002FB07
J 0
(2525 5775);
DISPLAY 0.510638 (2525 5775);
PAINT WHITE (2525 5775);
DISPLAY INVISIBLE (2525 5775);
FORCEPROP 1 LAST LOCATION R76
J 0
(2150 5750);
DISPLAY 0.702128 (2150 5750);
PAINT YELLOW (2150 5750);
FORCEPROP 0 LAST $SEC 1
J 0
(2300 5825);
DISPLAY INVISIBLE (2300 5825);
FORCEPROP 0 LAST CDS_SEC 1
J 0
(2300 5825);
DISPLAY INVISIBLE (2300 5825);
FORCEPROP 1 LASTPIN (2350 5750) $PN 1
J 0
(2362 5762);
DISPLAY 0.808511 (2362 5762);
PAINT WHITE (2362 5762);
DISPLAY INVISIBLE (2362 5762);
FORCEPROP 1 LASTPIN (2550 5750) $PN 2
J 0
(2512 5762);
DISPLAY 0.808511 (2512 5762);
PAINT WHITE (2512 5762);
DISPLAY INVISIBLE (2512 5762);
FORCEADD Q_RES..1
R 2
(2450 5575);
FORCEPROP 1 LAST VALUE 0
J 0
(2625 5575);
DISPLAY 0.510638 (2625 5575);
PAINT SKYBLUE (2625 5575);
FORCEPROP 1 LAST TOLERANCE 5%
J 0
(2400 5500);
DISPLAY 0.510638 (2400 5500);
PAINT SKYBLUE (2400 5500);
FORCEPROP 1 LAST MATERIAL EMPTY
J 2
(2975 5575);
DISPLAY 0.510638 (2975 5575);
PAINT RED (2975 5575);
FORCEPROP 1 LAST WATTAGE 1/16W
J 0
(2225 5500);
DISPLAY 0.510638 (2225 5500);
PAINT SKYBLUE (2225 5500);
FORCEPROP 1 LAST PACK_TYPE 0402LF
J 0
(2500 5500);
DISPLAY 0.510638 (2500 5500);
PAINT SKYBLUE (2500 5500);
FORCEPROP 2 LAST CDS_LIB pure_quanta
J 2
(2450 5669);
DISPLAY INVISIBLE (2450 5669);
FORCEPROP 1 LAST PATH I231
J 2
(2500 5725);
DISPLAY 0.978723 (2500 5725);
PAINT WHITE (2500 5725);
DISPLAY INVISIBLE (2500 5725);
FORCEPROP 1 LAST PART_NUMBER CS00002JB13
J 2
(2400 5525);
DISPLAY 0.510638 (2400 5525);
PAINT WHITE (2400 5525);
DISPLAY INVISIBLE (2400 5525);
FORCEPROP 1 LAST LOCATION R63
J 0
(2150 5575);
DISPLAY 0.702128 (2150 5575);
PAINT YELLOW (2150 5575);
FORCEPROP 0 LAST $SEC 1
J 0
(2550 5650);
DISPLAY 0.680851 (2550 5650);
PAINT MONO (2550 5650);
DISPLAY INVISIBLE (2550 5650);
FORCEPROP 0 LAST CDS_SEC 1
J 0
(2550 5650);
DISPLAY 1.021277 (2550 5650);
DISPLAY INVISIBLE (2550 5650);
FORCEPROP 1 LASTPIN (2550 5575) $PN 1
R 2
J 0
(2538 5661);
DISPLAY 0.808511 (2538 5661);
PAINT WHITE (2538 5661);
DISPLAY INVISIBLE (2538 5661);
FORCEPROP 1 LASTPIN (2350 5575) $PN 2
R 2
J 0
(2388 5661);
DISPLAY 0.808511 (2388 5661);
PAINT WHITE (2388 5661);
DISPLAY INVISIBLE (2388 5661);
FORCEADD Q_RES..1
(2450 6125);
FORCEPROP 1 LAST MATERIAL CHIP
J 0
(2900 6125);
DISPLAY 0.510638 (2900 6125);
PAINT SKYBLUE (2900 6125);
FORCEPROP 1 LAST VALUE 2K
J 2
(2675 6125);
DISPLAY 0.510638 (2675 6125);
PAINT SKYBLUE (2675 6125);
FORCEPROP 1 LAST TOLERANCE 1%
J 0
(2400 6050);
DISPLAY 0.510638 (2400 6050);
PAINT SKYBLUE (2400 6050);
FORCEPROP 1 LAST WATTAGE 1/16W
J 0
(2225 6050);
DISPLAY 0.510638 (2225 6050);
PAINT SKYBLUE (2225 6050);
FORCEPROP 1 LAST PACK_TYPE 0402LF
J 0
(2500 6050);
DISPLAY 0.510638 (2500 6050);
PAINT SKYBLUE (2500 6050);
FORCEPROP 2 LAST CDS_LIB pure_quanta
J 0
(2450 6125);
DISPLAY INVISIBLE (2450 6125);
FORCEPROP 1 LAST PATH I232
J 0
(2400 6275);
DISPLAY 0.978723 (2400 6275);
PAINT WHITE (2400 6275);
DISPLAY INVISIBLE (2400 6275);
FORCEPROP 1 LAST PART_NUMBER CS22002FB07
J 0
(2525 6150);
DISPLAY 0.510638 (2525 6150);
PAINT WHITE (2525 6150);
DISPLAY INVISIBLE (2525 6150);
FORCEPROP 1 LAST LOCATION R82
J 0
(2150 6125);
DISPLAY 0.702128 (2150 6125);
PAINT YELLOW (2150 6125);
FORCEPROP 0 LAST $SEC 1
J 0
(2300 6200);
DISPLAY INVISIBLE (2300 6200);
FORCEPROP 0 LAST CDS_SEC 1
J 0
(2300 6200);
DISPLAY INVISIBLE (2300 6200);
FORCEPROP 1 LASTPIN (2350 6125) $PN 1
J 0
(2362 6137);
DISPLAY 0.808511 (2362 6137);
PAINT WHITE (2362 6137);
DISPLAY INVISIBLE (2362 6137);
FORCEPROP 1 LASTPIN (2550 6125) $PN 2
J 0
(2512 6137);
DISPLAY 0.808511 (2512 6137);
PAINT WHITE (2512 6137);
DISPLAY INVISIBLE (2512 6137);
FORCEADD Q_RES..1
R 2
(2450 5950);
FORCEPROP 1 LAST MATERIAL EMPTY
J 2
(3000 5950);
DISPLAY 0.510638 (3000 5950);
PAINT RED (3000 5950);
FORCEPROP 1 LAST VALUE 0
J 0
(2675 5950);
DISPLAY 0.510638 (2675 5950);
PAINT SKYBLUE (2675 5950);
FORCEPROP 1 LAST TOLERANCE 5%
J 0
(2400 5875);
DISPLAY 0.510638 (2400 5875);
PAINT SKYBLUE (2400 5875);
FORCEPROP 1 LAST WATTAGE 1/16W
J 0
(2225 5875);
DISPLAY 0.510638 (2225 5875);
PAINT SKYBLUE (2225 5875);
FORCEPROP 1 LAST PACK_TYPE 0402LF
J 0
(2500 5875);
DISPLAY 0.510638 (2500 5875);
PAINT SKYBLUE (2500 5875);
FORCEPROP 2 LAST CDS_LIB pure_quanta
J 2
(2450 6044);
DISPLAY INVISIBLE (2450 6044);
FORCEPROP 1 LAST PATH I233
J 2
(2500 6100);
DISPLAY 0.978723 (2500 6100);
PAINT WHITE (2500 6100);
DISPLAY INVISIBLE (2500 6100);
FORCEPROP 1 LAST PART_NUMBER CS00002JB13
J 2
(2400 5900);
DISPLAY 0.510638 (2400 5900);
PAINT WHITE (2400 5900);
DISPLAY INVISIBLE (2400 5900);
FORCEPROP 1 LAST LOCATION R64
J 0
(2150 5950);
DISPLAY 0.702128 (2150 5950);
PAINT YELLOW (2150 5950);
FORCEPROP 0 LAST $SEC 1
J 0
(2550 6025);
DISPLAY 0.680851 (2550 6025);
PAINT MONO (2550 6025);
DISPLAY INVISIBLE (2550 6025);
FORCEPROP 0 LAST CDS_SEC 1
J 0
(2550 6025);
DISPLAY 1.021277 (2550 6025);
DISPLAY INVISIBLE (2550 6025);
FORCEPROP 1 LASTPIN (2550 5950) $PN 1
R 2
J 0
(2538 6036);
DISPLAY 0.808511 (2538 6036);
PAINT WHITE (2538 6036);
DISPLAY INVISIBLE (2538 6036);
FORCEPROP 1 LASTPIN (2350 5950) $PN 2
R 2
J 0
(2388 6036);
DISPLAY 0.808511 (2388 6036);
PAINT WHITE (2388 6036);
DISPLAY INVISIBLE (2388 6036);
FORCEADD Q_RES..1
(-200 3300);
FORCEPROP 1 LAST PART_NUMBER CS41002FB09
J 0
(-250 3375);
DISPLAY 0.510638 (-250 3375);
PAINT WHITE (-250 3375);
FORCEPROP 1 LAST TOLERANCE 1%
J 0
(-200 3200);
DISPLAY 0.510638 (-200 3200);
PAINT SKYBLUE (-200 3200);
FORCEPROP 1 LAST VALUE 100K
J 2
(-225 3200);
DISPLAY 0.510638 (-225 3200);
PAINT SKYBLUE (-225 3200);
FORCEPROP 1 LAST WATTAGE 1/16W
J 2
(-225 3150);
DISPLAY 0.510638 (-225 3150);
PAINT SKYBLUE (-225 3150);
FORCEPROP 1 LAST MATERIAL CHIP
J 0
(-200 3150);
DISPLAY 0.510638 (-200 3150);
PAINT SKYBLUE (-200 3150);
FORCEPROP 1 LAST PACK_TYPE 0402LF
J 0
(50 3150);
DISPLAY 0.510638 (50 3150);
PAINT SKYBLUE (50 3150);
FORCEPROP 2 LAST CDS_LIB pure_quanta
J 0
(-200 3300);
DISPLAY INVISIBLE (-200 3300);
FORCEPROP 1 LAST PATH I234
J 0
(-250 3450);
DISPLAY 0.978723 (-250 3450);
PAINT WHITE (-250 3450);
DISPLAY INVISIBLE (-250 3450);
FORCEPROP 1 LAST LOCATION R823
J 0
(-575 3300);
DISPLAY 0.702128 (-575 3300);
PAINT YELLOW (-575 3300);
FORCEPROP 0 LAST $SEC 1
J 0
(-250 3400);
DISPLAY 0.680851 (-250 3400);
PAINT MONO (-250 3400);
DISPLAY INVISIBLE (-250 3400);
FORCEPROP 0 LAST CDS_SEC 1
J 0
(-550 3350);
DISPLAY INVISIBLE (-550 3350);
FORCEPROP 1 LASTPIN (-300 3300) $PN 1
J 0
(-288 3312);
DISPLAY 0.808511 (-288 3312);
PAINT WHITE (-288 3312);
DISPLAY INVISIBLE (-288 3312);
FORCEPROP 1 LASTPIN (-100 3300) $PN 2
J 0
(-138 3312);
DISPLAY 0.808511 (-138 3312);
PAINT WHITE (-138 3312);
DISPLAY INVISIBLE (-138 3312);
FORCEADD OFFPAGE..2
(1450 3300);
FORCEPROP 2 LAST $XR0 13 
J 0
(1639 3300);
DISPLAY 0.638298 (1639 3300);
PAINT MONO (1639 3300);
FORCEPROP 2 LAST $XR1 10 
J 0
(1729 3300);
DISPLAY 0.638298 (1729 3300);
PAINT MONO (1729 3300);
FORCEPROP 2 LAST CDS_LIB standard
J 0
(1450 3300);
DISPLAY INVISIBLE (1450 3300);
FORCEPROP 1 LAST OFFPAGE TRUE
J 0
(1775 3175);
DISPLAY 0.872340 (1775 3175);
PAINT GREEN (1775 3175);
DISPLAY INVISIBLE (1775 3175);
FORCEPROP 1 LAST COMMENT_BODY TRUE
J 0
(1405 3205);
DISPLAY 0.872340 (1405 3205);
PAINT PEACH (1405 3205);
DISPLAY INVISIBLE (1405 3205);
FORCEPROP 2 LAST PATH I235
J 0
(1700 3350);
DISPLAY 1.021277 (1700 3350);
DISPLAY INVISIBLE (1700 3350);
FORCEADD OFFPAGE..2
(-1675 2975);
FORCEPROP 2 LAST $XR3 36 
J 0
(-1216 2975);
DISPLAY 0.638298 (-1216 2975);
PAINT MONO (-1216 2975);
FORCEPROP 2 LAST $XR0 13 
J 0
(-1486 2975);
DISPLAY 0.638298 (-1486 2975);
PAINT MONO (-1486 2975);
FORCEPROP 2 LAST $XR1 10 
J 0
(-1396 2975);
DISPLAY 0.638298 (-1396 2975);
PAINT MONO (-1396 2975);
FORCEPROP 2 LAST $XR2 35 
J 0
(-1306 2975);
DISPLAY 0.638298 (-1306 2975);
PAINT MONO (-1306 2975);
FORCEPROP 2 LAST CDS_LIB standard
J 0
(-1675 2975);
DISPLAY INVISIBLE (-1675 2975);
FORCEPROP 1 LAST OFFPAGE TRUE
J 0
(-1350 2850);
DISPLAY 0.872340 (-1350 2850);
PAINT GREEN (-1350 2850);
DISPLAY INVISIBLE (-1350 2850);
FORCEPROP 1 LAST COMMENT_BODY TRUE
J 0
(-1720 2880);
DISPLAY 0.872340 (-1720 2880);
PAINT PEACH (-1720 2880);
DISPLAY INVISIBLE (-1720 2880);
FORCEPROP 2 LAST PATH I237
J 0
(-1500 3050);
DISPLAY 1.021277 (-1500 3050);
DISPLAY INVISIBLE (-1500 3050);
FORCEADD Q_RES..1
(-3325 2975);
FORCEPROP 1 LAST MATERIAL EMPTY
J 0
(-2975 2975);
DISPLAY 0.510638 (-2975 2975);
PAINT RED (-2975 2975);
FORCEPROP 1 LAST VALUE 4.7K
J 0
(-3150 2975);
DISPLAY 0.510638 (-3150 2975);
PAINT SKYBLUE (-3150 2975);
FORCEPROP 2 LAST CDS_LIB pure_quanta
J 0
(-3325 2975);
DISPLAY INVISIBLE (-3325 2975);
FORCEPROP 1 LAST TOLERANCE 1%
J 0
(-3325 2875);
DISPLAY 0.510638 (-3325 2875);
PAINT SKYBLUE (-3325 2875);
DISPLAY INVISIBLE (-3325 2875);
FORCEPROP 1 LAST PATH I241
J 0
(-3375 3125);
DISPLAY 0.978723 (-3375 3125);
PAINT WHITE (-3375 3125);
DISPLAY INVISIBLE (-3375 3125);
FORCEPROP 1 LAST WATTAGE 1/16W
J 2
(-3350 2825);
DISPLAY 0.510638 (-3350 2825);
PAINT SKYBLUE (-3350 2825);
DISPLAY INVISIBLE (-3350 2825);
FORCEPROP 1 LAST PACK_TYPE 0402LF
J 0
(-3075 2825);
DISPLAY 0.510638 (-3075 2825);
PAINT SKYBLUE (-3075 2825);
DISPLAY INVISIBLE (-3075 2825);
FORCEPROP 1 LAST PART_NUMBER CS24702FB06
J 0
(-3375 3075);
DISPLAY 0.510638 (-3375 3075);
PAINT WHITE (-3375 3075);
DISPLAY INVISIBLE (-3375 3075);
FORCEPROP 1 LAST LOCATION R828
J 0
(-3600 2975);
DISPLAY 0.702128 (-3600 2975);
PAINT YELLOW (-3600 2975);
FORCEPROP 0 LAST $SEC 1
J 0
(-3675 3025);
DISPLAY INVISIBLE (-3675 3025);
FORCEPROP 0 LAST CDS_SEC 1
J 0
(-3675 3025);
DISPLAY INVISIBLE (-3675 3025);
FORCEPROP 1 LASTPIN (-3425 2975) $PN 1
J 0
(-3413 2987);
DISPLAY 0.808511 (-3413 2987);
PAINT WHITE (-3413 2987);
DISPLAY INVISIBLE (-3413 2987);
FORCEPROP 1 LASTPIN (-3225 2975) $PN 2
J 0
(-3263 2987);
DISPLAY 0.808511 (-3263 2987);
PAINT WHITE (-3263 2987);
DISPLAY INVISIBLE (-3263 2987);
FORCEADD OFFPAGE..2
(-1675 2750);
FORCEPROP 2 LAST $XR3 34 
J 0
(-1216 2750);
DISPLAY 0.638298 (-1216 2750);
PAINT MONO (-1216 2750);
FORCEPROP 2 LAST $XR2 15 
J 0
(-1306 2750);
DISPLAY 0.638298 (-1306 2750);
PAINT MONO (-1306 2750);
FORCEPROP 2 LAST $XR1 50 
J 0
(-1396 2750);
DISPLAY 0.638298 (-1396 2750);
PAINT MONO (-1396 2750);
FORCEPROP 2 LAST $XR0 10 
J 0
(-1486 2750);
DISPLAY 0.638298 (-1486 2750);
PAINT MONO (-1486 2750);
FORCEPROP 2 LAST CDS_LIB standard
J 0
(-1675 2750);
DISPLAY INVISIBLE (-1675 2750);
FORCEPROP 2 LAST PATH I244
J 0
(-1500 2825);
DISPLAY 1.021277 (-1500 2825);
DISPLAY INVISIBLE (-1500 2825);
FORCEPROP 1 LAST COMMENT_BODY TRUE
J 0
(-1720 2655);
DISPLAY 0.872340 (-1720 2655);
PAINT PEACH (-1720 2655);
DISPLAY INVISIBLE (-1720 2655);
FORCEPROP 1 LAST OFFPAGE TRUE
J 0
(-1350 2625);
DISPLAY 0.872340 (-1350 2625);
PAINT GREEN (-1350 2625);
DISPLAY INVISIBLE (-1350 2625);
FORCEADD Q_RES..1
(-3325 2750);
FORCEPROP 1 LAST MATERIAL CHIP
J 0
(-2975 2750);
DISPLAY 0.510638 (-2975 2750);
PAINT SKYBLUE (-2975 2750);
FORCEPROP 1 LAST VALUE 4.7K
J 0
(-3150 2750);
DISPLAY 0.510638 (-3150 2750);
PAINT SKYBLUE (-3150 2750);
FORCEPROP 2 LAST CDS_LIB pure_quanta
J 0
(-3325 2750);
DISPLAY INVISIBLE (-3325 2750);
FORCEPROP 1 LAST PATH I245
J 0
(-3375 2900);
DISPLAY 0.978723 (-3375 2900);
PAINT WHITE (-3375 2900);
DISPLAY INVISIBLE (-3375 2900);
FORCEPROP 1 LAST PART_NUMBER CS24702FB06
J 0
(-3375 2850);
DISPLAY 0.510638 (-3375 2850);
PAINT WHITE (-3375 2850);
DISPLAY INVISIBLE (-3375 2850);
FORCEPROP 1 LAST PACK_TYPE 0402LF
J 0
(-3075 2600);
DISPLAY 0.510638 (-3075 2600);
PAINT SKYBLUE (-3075 2600);
DISPLAY INVISIBLE (-3075 2600);
FORCEPROP 1 LAST WATTAGE 1/16W
J 2
(-3350 2600);
DISPLAY 0.510638 (-3350 2600);
PAINT SKYBLUE (-3350 2600);
DISPLAY INVISIBLE (-3350 2600);
FORCEPROP 1 LAST TOLERANCE 1%
J 0
(-3325 2650);
DISPLAY 0.510638 (-3325 2650);
PAINT SKYBLUE (-3325 2650);
DISPLAY INVISIBLE (-3325 2650);
FORCEPROP 1 LAST LOCATION R81
J 0
(-3600 2750);
DISPLAY 0.702128 (-3600 2750);
PAINT YELLOW (-3600 2750);
FORCEPROP 0 LAST $SEC 1
J 0
(-3650 2800);
DISPLAY 0.680851 (-3650 2800);
PAINT MONO (-3650 2800);
DISPLAY INVISIBLE (-3650 2800);
FORCEPROP 0 LAST CDS_SEC 1
J 0
(-3650 2800);
DISPLAY 1.021277 (-3650 2800);
DISPLAY INVISIBLE (-3650 2800);
FORCEPROP 1 LASTPIN (-3425 2750) $PN 1
J 0
(-3413 2762);
DISPLAY 0.808511 (-3413 2762);
PAINT WHITE (-3413 2762);
DISPLAY INVISIBLE (-3413 2762);
FORCEPROP 1 LASTPIN (-3225 2750) $PN 2
J 0
(-3263 2762);
DISPLAY 0.808511 (-3263 2762);
PAINT WHITE (-3263 2762);
DISPLAY INVISIBLE (-3263 2762);
FORCEADD UNIVERSAL_POWER..1
(-3950 7325);
FORCEPROP 3 LASTPIN (-3950 7275) SIG_NAME P3V3_RGM\g
J 0
(-3940 7285);
DISPLAY 0.659574 (-3940 7285);
PAINT MONO (-3940 7285);
DISPLAY INVISIBLE (-3940 7285);
FORCEPROP 1 LAST HDL_POWER P3V3_RGM
J 1
(-3950 7375);
DISPLAY 0.702128 (-3950 7375);
PAINT GREEN (-3950 7375);
FORCEPROP 1 LAST PATH I254
J 0
(-3900 7350);
DISPLAY 0.872340 (-3900 7350);
PAINT AQUA (-3900 7350);
DISPLAY INVISIBLE (-3900 7350);
FORCEPROP 2 LAST CDS_LIB logical_power
J 0
(-3950 7325);
DISPLAY INVISIBLE (-3950 7325);
FORCEADD OFFPAGE..2
(-1675 2525);
FORCEPROP 2 LAST $XR0 13 
J 0
(-1486 2525);
DISPLAY 0.638298 (-1486 2525);
PAINT MONO (-1486 2525);
FORCEPROP 2 LAST $XR1 34 
J 0
(-1396 2525);
DISPLAY 0.638298 (-1396 2525);
PAINT MONO (-1396 2525);
FORCEPROP 1 LAST OFFPAGE TRUE
J 0
(-1350 2400);
DISPLAY 0.872340 (-1350 2400);
PAINT GREEN (-1350 2400);
DISPLAY INVISIBLE (-1350 2400);
FORCEPROP 1 LAST COMMENT_BODY TRUE
J 0
(-1720 2430);
DISPLAY 0.872340 (-1720 2430);
PAINT PEACH (-1720 2430);
DISPLAY INVISIBLE (-1720 2430);
FORCEPROP 2 LAST PATH I255
J 0
(-1500 2600);
DISPLAY 0.680851 (-1500 2600);
DISPLAY INVISIBLE (-1500 2600);
FORCEPROP 2 LAST CDS_LIB standard
J 0
(-1675 2525);
DISPLAY INVISIBLE (-1675 2525);
FORCEADD Q_RES..1
(-3325 2525);
FORCEPROP 1 LAST VALUE 4.7K
J 0
(-3150 2525);
DISPLAY 0.510638 (-3150 2525);
PAINT SKYBLUE (-3150 2525);
FORCEPROP 1 LAST MATERIAL CHIP
J 0
(-2975 2525);
DISPLAY 0.510638 (-2975 2525);
PAINT SKYBLUE (-2975 2525);
FORCEPROP 1 LAST TOLERANCE 1%
J 0
(-3325 2425);
DISPLAY 0.510638 (-3325 2425);
PAINT SKYBLUE (-3325 2425);
DISPLAY INVISIBLE (-3325 2425);
FORCEPROP 1 LAST WATTAGE 1/16W
J 2
(-3350 2375);
DISPLAY 0.510638 (-3350 2375);
PAINT SKYBLUE (-3350 2375);
DISPLAY INVISIBLE (-3350 2375);
FORCEPROP 1 LAST PACK_TYPE 0402LF
J 0
(-3075 2375);
DISPLAY 0.510638 (-3075 2375);
PAINT SKYBLUE (-3075 2375);
DISPLAY INVISIBLE (-3075 2375);
FORCEPROP 1 LAST PART_NUMBER CS24702FB06
J 0
(-3375 2625);
DISPLAY 0.510638 (-3375 2625);
PAINT WHITE (-3375 2625);
DISPLAY INVISIBLE (-3375 2625);
FORCEPROP 1 LAST PATH I256
J 0
(-3375 2675);
DISPLAY 0.978723 (-3375 2675);
PAINT WHITE (-3375 2675);
DISPLAY INVISIBLE (-3375 2675);
FORCEPROP 2 LAST CDS_LIB pure_quanta
J 0
(-3325 2525);
DISPLAY INVISIBLE (-3325 2525);
FORCEPROP 1 LAST LOCATION R169
J 0
(-3600 2525);
DISPLAY 0.702128 (-3600 2525);
PAINT YELLOW (-3600 2525);
FORCEPROP 1 LASTPIN (-3425 2525) $PN 1
J 0
(-3413 2537);
DISPLAY 0.787234 (-3413 2537);
PAINT MONO (-3413 2537);
FORCEPROP 1 LASTPIN (-3225 2525) $PN 2
J 0
(-3263 2537);
DISPLAY 0.787234 (-3263 2537);
PAINT MONO (-3263 2537);
FORCEPROP 0 LAST $SEC 1
J 0
(-3650 2575);
DISPLAY 0.680851 (-3650 2575);
PAINT MONO (-3650 2575);
DISPLAY INVISIBLE (-3650 2575);
FORCEPROP 0 LAST CDS_SEC 1
J 0
(-3650 2575);
DISPLAY 0.680851 (-3650 2575);
DISPLAY INVISIBLE (-3650 2575);
FORCEADD OFFPAGE..2
(-1675 5825);
FORCEPROP 2 LAST $XR1 13 
J 0
(-1396 5825);
DISPLAY 0.638298 (-1396 5825);
PAINT MONO (-1396 5825);
FORCEPROP 2 LAST $XR0 35 
J 0
(-1486 5825);
DISPLAY 0.638298 (-1486 5825);
PAINT MONO (-1486 5825);
FORCEPROP 2 LAST CDS_LIB standard
J 0
(-1675 5825);
DISPLAY INVISIBLE (-1675 5825);
FORCEPROP 1 LAST OFFPAGE TRUE
J 0
(-1350 5700);
DISPLAY 0.872340 (-1350 5700);
PAINT GREEN (-1350 5700);
DISPLAY INVISIBLE (-1350 5700);
FORCEPROP 1 LAST COMMENT_BODY TRUE
J 0
(-1720 5730);
DISPLAY 0.872340 (-1720 5730);
PAINT PEACH (-1720 5730);
DISPLAY INVISIBLE (-1720 5730);
FORCEPROP 2 LAST PATH I38
J 0
(-1475 5875);
DISPLAY 1.021277 (-1475 5875);
DISPLAY INVISIBLE (-1475 5875);
FORCEADD OFFPAGE..2
(1450 3625);
FORCEPROP 2 LAST $XR0 10 
J 0
(1639 3625);
DISPLAY 0.638298 (1639 3625);
PAINT MONO (1639 3625);
FORCEPROP 2 LAST $XR1 13 
J 0
(1729 3625);
DISPLAY 0.638298 (1729 3625);
PAINT MONO (1729 3625);
FORCEPROP 2 LAST $XR2 28 
J 0
(1819 3625);
DISPLAY 0.638298 (1819 3625);
PAINT MONO (1819 3625);
FORCEPROP 2 LAST $XR3 35 
J 0
(1909 3625);
DISPLAY 0.638298 (1909 3625);
PAINT MONO (1909 3625);
FORCEPROP 2 LAST CDS_LIB standard
J 0
(1450 3625);
DISPLAY INVISIBLE (1450 3625);
FORCEPROP 1 LAST OFFPAGE TRUE
J 0
(1775 3500);
DISPLAY 0.872340 (1775 3500);
PAINT GREEN (1775 3500);
DISPLAY INVISIBLE (1775 3500);
FORCEPROP 1 LAST COMMENT_BODY TRUE
J 0
(1405 3530);
DISPLAY 0.872340 (1405 3530);
PAINT PEACH (1405 3530);
DISPLAY INVISIBLE (1405 3530);
FORCEPROP 2 LAST PATH I42
J 0
(1650 3675);
DISPLAY 1.021277 (1650 3675);
DISPLAY INVISIBLE (1650 3675);
FORCEADD VCCAUX15..1
(-3950 6575);
FORCEPROP 3 LASTPIN (-3950 6525) SIG_NAME P3V3_AUX\g
J 0
(-3940 6535);
DISPLAY 0.659574 (-3940 6535);
PAINT MONO (-3940 6535);
DISPLAY INVISIBLE (-3940 6535);
FORCEPROP 1 LAST HDL_POWER P3V3_AUX
J 1
(-3950 6625);
DISPLAY 0.702128 (-3950 6625);
PAINT GREEN (-3950 6625);
FORCEPROP 1 LAST PATH I56
J 0
(-3900 6600);
DISPLAY 0.872340 (-3900 6600);
PAINT AQUA (-3900 6600);
DISPLAY INVISIBLE (-3900 6600);
FORCEPROP 2 LAST CDS_LIB logical_power
J 0
(-3950 6575);
DISPLAY INVISIBLE (-3950 6575);
FORCEADD UNIVERSAL_GND..1
(1850 4725);
FORCEPROP 3 LASTPIN (1850 4775) SIG_NAME GND\g
J 0
(1860 4785);
DISPLAY 0.659574 (1860 4785);
PAINT MONO (1860 4785);
DISPLAY INVISIBLE (1860 4785);
FORCEPROP 2 LAST CDS_LIB logical_power
J 0
(1850 4725);
DISPLAY INVISIBLE (1850 4725);
FORCEPROP 1 LAST HDL_POWER GND
J 1
(1875 4650);
DISPLAY 0.702128 (1875 4650);
PAINT GREEN (1875 4650);
DISPLAY INVISIBLE (1875 4650);
FORCEPROP 1 LAST PATH I58
J 0
(1925 4725);
DISPLAY 0.872340 (1925 4725);
PAINT AQUA (1925 4725);
DISPLAY INVISIBLE (1925 4725);
FORCEADD OFFPAGE..2
(-1675 4625);
FORCEPROP 2 LAST $XR0 10 
J 0
(-1486 4625);
DISPLAY 0.638298 (-1486 4625);
PAINT MONO (-1486 4625);
FORCEPROP 2 LAST $XR1 13 
J 0
(-1396 4625);
DISPLAY 0.638298 (-1396 4625);
PAINT MONO (-1396 4625);
FORCEPROP 2 LAST $XR2 35 
J 0
(-1306 4625);
DISPLAY 0.638298 (-1306 4625);
PAINT MONO (-1306 4625);
FORCEPROP 2 LAST CDS_LIB standard
J 0
(-1675 4625);
DISPLAY INVISIBLE (-1675 4625);
FORCEPROP 1 LAST OFFPAGE TRUE
J 0
(-1350 4500);
DISPLAY 0.872340 (-1350 4500);
PAINT GREEN (-1350 4500);
DISPLAY INVISIBLE (-1350 4500);
FORCEPROP 1 LAST COMMENT_BODY TRUE
J 0
(-1720 4530);
DISPLAY 0.872340 (-1720 4530);
PAINT PEACH (-1720 4530);
DISPLAY INVISIBLE (-1720 4530);
FORCEPROP 2 LAST PATH I63
J 0
(-1475 4675);
DISPLAY 1.021277 (-1475 4675);
DISPLAY INVISIBLE (-1475 4675);
FORCEADD OFFPAGE..2
(1450 3950);
FORCEPROP 2 LAST $XR0 10 
J 0
(1639 3950);
DISPLAY 0.638298 (1639 3950);
PAINT MONO (1639 3950);
FORCEPROP 2 LAST $XR1 13 
J 0
(1729 3950);
DISPLAY 0.638298 (1729 3950);
PAINT MONO (1729 3950);
FORCEPROP 2 LAST $XR2 22 
J 0
(1819 3950);
DISPLAY 0.638298 (1819 3950);
PAINT MONO (1819 3950);
FORCEPROP 2 LAST $XR3 28 
J 0
(1909 3950);
DISPLAY 0.638298 (1909 3950);
PAINT MONO (1909 3950);
FORCEPROP 2 LAST $XR4 34 
J 0
(1999 3950);
DISPLAY 0.638298 (1999 3950);
PAINT MONO (1999 3950);
FORCEPROP 2 LAST CDS_LIB standard
J 0
(1450 3950);
DISPLAY INVISIBLE (1450 3950);
FORCEPROP 1 LAST OFFPAGE TRUE
J 0
(1775 3825);
DISPLAY 0.872340 (1775 3825);
PAINT GREEN (1775 3825);
DISPLAY INVISIBLE (1775 3825);
FORCEPROP 1 LAST COMMENT_BODY TRUE
J 0
(1405 3855);
DISPLAY 0.872340 (1405 3855);
PAINT PEACH (1405 3855);
DISPLAY INVISIBLE (1405 3855);
FORCEPROP 2 LAST PATH I72
J 0
(1650 4000);
DISPLAY 1.021277 (1650 4000);
DISPLAY INVISIBLE (1650 4000);
FORCEADD OFFPAGE..2
(-1675 3425);
FORCEPROP 2 LAST $XR0 12 
J 0
(-1486 3425);
DISPLAY 0.638298 (-1486 3425);
PAINT MONO (-1486 3425);
FORCEPROP 2 LAST $XR1 10 
J 0
(-1396 3425);
DISPLAY 0.638298 (-1396 3425);
PAINT MONO (-1396 3425);
FORCEPROP 2 LAST CDS_LIB standard
J 0
(-1675 3425);
DISPLAY INVISIBLE (-1675 3425);
FORCEPROP 1 LAST OFFPAGE TRUE
J 0
(-1350 3300);
DISPLAY 0.872340 (-1350 3300);
PAINT GREEN (-1350 3300);
DISPLAY INVISIBLE (-1350 3300);
FORCEPROP 1 LAST COMMENT_BODY TRUE
J 0
(-1720 3330);
DISPLAY 0.872340 (-1720 3330);
PAINT PEACH (-1720 3330);
DISPLAY INVISIBLE (-1720 3330);
FORCEPROP 2 LAST PATH I76
J 0
(-1350 3475);
DISPLAY 1.021277 (-1350 3475);
DISPLAY INVISIBLE (-1350 3475);
FORCEADD QUANTA_TITLE_BLOCK_C..1
(5100 1625);
FORCEPROP 0 LAST CDS_CON_LAST_MODIFIED Fri Aug 25 17:25:36 2023
J 0
(3215 1640);
DISPLAY INVISIBLE (3215 1640);
FORCEPROP 2 LAST Q_DEPT 
J 1
(1337 1674);
DISPLAY 1.957447 (1337 1674);
PAINT GREEN (1337 1674);
FORCEPROP 1 LAST CUSTOM_TXT_CDS <CON_LAST_MODIFIED>
J 0
(3215 1640);
DISPLAY 0.978723 (3215 1640);
FORCEPROP 2 LAST CUSTOM_TXT_CDS <XR_PAGE_TITLE>
J 0
(-2790 6875);
DISPLAY 0.638298 (-2790 6875);
PAINT PINK (-2790 6875);
DISPLAY INVISIBLE (-2790 6875);
FORCEPROP 1 LAST CUSTOM_TXT_CDS <NAME_2>
J 0
(1925 1675);
FORCEPROP 1 LAST CUSTOM_TXT_CDS <NAME_1>
J 0
(1925 1800);
FORCEPROP 1 LAST CUSTOM_TXT_CDS <Q_NUMBER>
J 0
(3697 1728);
DISPLAY 1.212766 (3697 1728);
FORCEPROP 1 LAST CUSTOM_TXT_CDS <Q_PROJ>
J 0
(2718 1727);
DISPLAY 1.212766 (2718 1727);
FORCEPROP 1 LAST CUSTOM_TXT_CDS <Q_REV>
J 0
(4916 1728);
DISPLAY 1.212766 (4916 1728);
FORCEPROP 1 LAST CUSTOM_TXT_CDS <CON_PAGE_NUM> OF <CON_TOTAL_PAGES>
J 0
(4654 1643);
DISPLAY 0.978723 (4654 1643);
FORCEPROP 1 LAST Q_TITLE OCP 3.0 SCM FINGER 2/2
J 0
(-4266 1651);
DISPLAY 2.446809 (-4266 1651);
PAINT GREEN (-4266 1651);
FORCEPROP 2 LAST CDS_XR_PAGE_TITLE CR-11 : @SCM_LIB.SCM(SCH_1):PAGE11
J 0
(-2790 6875);
DISPLAY 0.638298 (-2790 6875);
PAINT PINK (-2790 6875);
DISPLAY INVISIBLE (-2790 6875);
FORCEPROP 2 LAST CDS_LIB pure_quanta
J 0
(5100 1625);
DISPLAY INVISIBLE (5100 1625);
FORCEPROP 1 LAST CDS_LMAN_SYM_OUTLINE -9475,6775,100,-125
J 0
(5100 1625);
DISPLAY 0.468085 (5100 1625);
PAINT GREEN (5100 1625);
DISPLAY INVISIBLE (5100 1625);
FORCEPROP 2 LAST PAGE_BORDER TRUE
J 0
(-2790 6875);
DISPLAY 0.638298 (-2790 6875);
PAINT PINK (-2790 6875);
DISPLAY INVISIBLE (-2790 6875);
FORCEPROP 1 LAST COMMENT_BODY TRUE
J 0
(5112 1612);
DISPLAY 0.978723 (5112 1612);
PAINT PEACH (5112 1612);
DISPLAY INVISIBLE (5112 1612);
FORCEADD DNS..2
(-3350 3800);
PAINT RED (-3350 3800);
FORCEPROP 2 LAST CDS_LIB mstr_misc
J 0
(-3350 3800);
DISPLAY INVISIBLE (-3350 3800);
FORCEPROP 1 LAST COMMENT_BODY TRUE
R 1
J 0
(-3275 3575);
DISPLAY 0.872340 (-3275 3575);
PAINT PEACH (-3275 3575);
DISPLAY INVISIBLE (-3275 3575);
FORCEADD DNS..2
(-3325 4425);
PAINT RED (-3325 4425);
FORCEPROP 2 LAST CDS_LIB mstr_misc
J 0
(-3325 4425);
DISPLAY INVISIBLE (-3325 4425);
FORCEPROP 1 LAST COMMENT_BODY TRUE
R 1
J 0
(-3250 4200);
DISPLAY 0.872340 (-3250 4200);
PAINT PEACH (-3250 4200);
DISPLAY INVISIBLE (-3250 4200);
FORCEADD DNS..2
(2450 5600);
PAINT RED (2450 5600);
FORCEPROP 2 LAST CDS_LIB mstr_misc
J 0
(2450 5600);
DISPLAY INVISIBLE (2450 5600);
FORCEPROP 1 LAST COMMENT_BODY TRUE
R 1
J 0
(2525 5375);
DISPLAY 0.872340 (2525 5375);
PAINT PEACH (2525 5375);
DISPLAY INVISIBLE (2525 5375);
FORCEADD DNS..2
(2450 5925);
PAINT RED (2450 5925);
FORCEPROP 2 LAST CDS_LIB mstr_misc
J 0
(2450 5925);
DISPLAY INVISIBLE (2450 5925);
FORCEPROP 1 LAST COMMENT_BODY TRUE
R 1
J 0
(2525 5700);
DISPLAY 0.872340 (2525 5700);
PAINT PEACH (2525 5700);
DISPLAY INVISIBLE (2525 5700);
FORCEADD DNS..2
(-200 3600);
PAINT RED (-200 3600);
FORCEPROP 2 LAST CDS_LIB mstr_misc
J 0
(-200 3600);
DISPLAY INVISIBLE (-200 3600);
FORCEPROP 1 LAST COMMENT_BODY TRUE
R 1
J 0
(-125 3375);
DISPLAY 0.872340 (-125 3375);
PAINT PEACH (-125 3375);
DISPLAY INVISIBLE (-125 3375);
FORCEADD DNS..2
(-3300 2975);
PAINT RED (-3300 2975);
FORCEPROP 1 LAST COMMENT_BODY TRUE
R 1
J 0
(-3225 2750);
DISPLAY 0.872340 (-3225 2750);
PAINT PEACH (-3225 2750);
DISPLAY INVISIBLE (-3225 2750);
FORCEPROP 2 LAST CDS_LIB mstr_misc
J 0
(-3300 2975);
DISPLAY INVISIBLE (-3300 2975);
FORCEADD DNS..2
(-3300 6225);
PAINT RED (-3300 6225);
FORCEPROP 1 LAST COMMENT_BODY TRUE
R 1
J 0
(-3225 6000);
DISPLAY 0.872340 (-3225 6000);
PAINT PEACH (-3225 6000);
DISPLAY INVISIBLE (-3225 6000);
FORCEPROP 2 LAST CDS_LIB mstr_misc
J 0
(-3300 6225);
DISPLAY INVISIBLE (-3300 6225);
FORCEADD DNS..2
(-3300 6025);
PAINT RED (-3300 6025);
FORCEPROP 1 LAST COMMENT_BODY TRUE
R 1
J 0
(-3225 5800);
DISPLAY 0.872340 (-3225 5800);
PAINT PEACH (-3225 5800);
DISPLAY INVISIBLE (-3225 5800);
FORCEPROP 2 LAST CDS_LIB mstr_misc
J 0
(-3300 6025);
DISPLAY INVISIBLE (-3300 6025);
FORCEADD DNS..2
(-3350 6975);
PAINT RED (-3350 6975);
FORCEPROP 1 LAST COMMENT_BODY TRUE
R 1
J 0
(-3275 6750);
DISPLAY 0.872340 (-3275 6750);
PAINT PEACH (-3275 6750);
DISPLAY INVISIBLE (-3275 6750);
FORCEPROP 2 LAST CDS_LIB mstr_misc
J 0
(-3350 6975);
DISPLAY INVISIBLE (-3350 6975);
WIRE 16 -1 (1975 6125)(1975 6575);
WIRE 16 -1 (2350 6125)(1975 6125);
WIRE 16 -1 (1975 6125)(1975 5750);
WIRE 16 -1 (-3950 6225)(-3950 6525);
WIRE 16 -1 (-3425 6225)(-3950 6225);
WIRE 16 -1 (-3950 6225)(-3950 6025);
WIRE 16 -1 (-3950 7275)(-3950 6975);
WIRE 16 -1 (1850 4775)(1850 5575);
WIRE 16 -1 (-825 2975)(-825 3300);
WIRE 16 -1 (1400 3300)(-100 3300);
FORCEPROP 2 LAST SIG_NAME FM_VIRTUAL_RESEAT
J 2
(1350 3310);
DISPLAY 0.808511 (1350 3310);
WIRE 16 -1 (1400 3625)(-100 3625);
FORCEPROP 2 LAST SIG_NAME PWRGD_SYS_PWROK
J 2
(1350 3635);
DISPLAY 0.808511 (1350 3635);
WIRE 16 -1 (1400 3950)(-100 3950);
FORCEPROP 2 LAST SIG_NAME PWRGD_PSU_AC_PWROK
J 2
(1350 3960);
DISPLAY 0.808511 (1350 3960);
WIRE 16 -1 (2550 5950)(3300 5950);
WIRE 16 -1 (3300 5950)(3300 6125);
WIRE 16 -1 (3300 6125)(4375 6125);
FORCEPROP 2 LAST SIG_NAME SGPIO_CLK_0
J 2
(4275 6135);
DISPLAY 0.808511 (4275 6135);
WIRE 16 -1 (2550 6125)(3300 6125);
WIRE 16 -1 (2550 5750)(3300 5750);
WIRE 16 -1 (4375 5750)(3300 5750);
FORCEPROP 2 LAST SIG_NAME SGPIO_CLK_1
J 2
(4275 5760);
DISPLAY 0.808511 (4275 5760);
WIRE 16 -1 (3300 5575)(3300 5750);
WIRE 16 -1 (2550 5575)(3300 5575);
WIRE 16 -1 (-1725 2525)(-3225 2525);
FORCEPROP 2 LAST SIG_NAME RST_PCA9548_SENSOR_N
J 0
(-2560 2535);
DISPLAY 0.851064 (-2560 2535);
WIRE 16 -1 (-1725 2750)(-3225 2750);
FORCEPROP 2 LAST SIG_NAME PWR_BTN_BMC_N
J 2
(-1775 2760);
DISPLAY 0.808511 (-1775 2760);
WIRE 16 -1 (-3225 2975)(-1725 2975);
FORCEPROP 2 LAST SIG_NAME RST_ROT_CPU_N
J 2
(-1775 2985);
DISPLAY 0.808511 (-1775 2985);
WIRE 16 -1 (-1725 3425)(-3225 3425);
FORCEPROP 2 LAST SIG_NAME SGPIO_DO_1
J 2
(-1775 3435);
DISPLAY 0.808511 (-1775 3435);
WIRE 16 -1 (-1725 3625)(-3225 3625);
FORCEPROP 2 LAST SIG_NAME SGPIO_DI_1
J 2
(-1775 3635);
DISPLAY 0.808511 (-1775 3635);
WIRE 16 -1 (-1725 3825)(-3250 3825);
FORCEPROP 2 LAST SIG_NAME SGPIO_LD_1
J 2
(-1775 3835);
DISPLAY 0.808511 (-1775 3835);
WIRE 16 -1 (-3225 4050)(-1725 4050);
FORCEPROP 2 LAST SIG_NAME SGPIO_DO_0
J 2
(-1775 4060);
DISPLAY 0.808511 (-1775 4060);
WIRE 16 -1 (-3225 4250)(-1725 4250);
FORCEPROP 2 LAST SIG_NAME SGPIO_DI_0
J 2
(-1775 4260);
DISPLAY 0.808511 (-1775 4260);
WIRE 16 -1 (-3225 4450)(-1725 4450);
FORCEPROP 2 LAST SIG_NAME SGPIO_LD_0
J 2
(-1775 4460);
DISPLAY 0.808511 (-1775 4460);
WIRE 16 -1 (-1725 4625)(-3200 4625);
FORCEPROP 2 LAST SIG_NAME IRQ_SGPIO_N
J 2
(-1800 4635);
DISPLAY 0.808511 (-1800 4635);
WIRE 16 -1 (-1725 4825)(-3200 4825);
FORCEPROP 2 LAST SIG_NAME RST_SGPIO_RESET_N
J 2
(-1785 4835);
DISPLAY 0.808511 (-1785 4835);
WIRE 16 -1 (-1725 5025)(-3225 5025);
FORCEPROP 2 LAST SIG_NAME RMII_CSRDV
J 2
(-1775 5035);
DISPLAY 0.808511 (-1775 5035);
WIRE 16 -1 (-1725 5225)(-3225 5225);
FORCEPROP 2 LAST SIG_NAME RMII_TXEN
J 2
(-1775 5235);
DISPLAY 0.808511 (-1775 5235);
WIRE 16 -1 (-1725 5425)(-3225 5425);
FORCEPROP 2 LAST SIG_NAME RMII_RXER
J 2
(-1775 5435);
DISPLAY 0.808511 (-1775 5435);
WIRE 16 -1 (-1725 5625)(-3225 5625);
FORCEPROP 2 LAST SIG_NAME FM_CPU_MSMI_CATERR_LVT3_N
J 2
(-1775 5635);
DISPLAY 0.808511 (-1775 5635);
WIRE 16 -1 (-1725 5825)(-3225 5825);
FORCEPROP 2 LAST SIG_NAME FM_THROTTLE_N
J 2
(-1775 5835);
DISPLAY 0.808511 (-1775 5835);
WIRE 16 -1 (-3225 6025)(-1725 6025);
FORCEPROP 2 LAST SIG_NAME SYS_PWRBTN_N
J 2
(-1775 6035);
DISPLAY 0.808511 (-1775 6035);
WIRE 16 -1 (-1725 6225)(-3225 6225);
FORCEPROP 2 LAST SIG_NAME LPC_ESPI_SEL
J 2
(-1750 6235);
DISPLAY 0.808511 (-1750 6235);
WIRE 16 -1 (-1725 6975)(-3275 6975);
FORCEPROP 2 LAST SIG_NAME RST_PLTRST_N
J 2
(-1775 6985);
DISPLAY 0.808511 (-1775 6985);
WIRE 16 -1 (2350 5750)(1975 5750);
WIRE 16 -1 (-300 3950)(-825 3950);
WIRE 16 -1 (-825 3950)(-825 3625);
WIRE 16 -1 (-300 3625)(-825 3625);
WIRE 16 -1 (-825 3300)(-825 3625);
WIRE 16 -1 (-300 3300)(-825 3300);
WIRE 16 -1 (-3475 6975)(-3950 6975);
WIRE 16 -1 (-3950 2525)(-3425 2525);
WIRE 16 -1 (-3950 2750)(-3950 2525);
WIRE 16 -1 (-3950 2750)(-3425 2750);
WIRE 16 -1 (-3950 2975)(-3950 2750);
WIRE 16 -1 (-3950 2975)(-3425 2975);
WIRE 16 -1 (-3950 2975)(-3950 3425);
WIRE 16 -1 (-3425 3425)(-3950 3425);
WIRE 16 -1 (-3950 3625)(-3950 3425);
WIRE 16 -1 (-3425 3625)(-3950 3625);
WIRE 16 -1 (-3950 3825)(-3950 3625);
WIRE 16 -1 (-3450 3825)(-3950 3825);
WIRE 16 -1 (-3950 4050)(-3950 3825);
WIRE 16 -1 (-3425 4050)(-3950 4050);
WIRE 16 -1 (-3950 4250)(-3950 4050);
WIRE 16 -1 (-3425 4250)(-3950 4250);
WIRE 16 -1 (-3950 4450)(-3950 4250);
WIRE 16 -1 (-3425 4450)(-3950 4450);
WIRE 16 -1 (-3950 4625)(-3950 4450);
WIRE 16 -1 (-3400 4625)(-3950 4625);
WIRE 16 -1 (-3950 4625)(-3950 4825);
WIRE 16 -1 (-3400 4825)(-3950 4825);
WIRE 16 -1 (-3950 5025)(-3950 4825);
WIRE 16 -1 (-3950 5025)(-3425 5025);
WIRE 16 -1 (-3950 5225)(-3950 5025);
WIRE 16 -1 (-3425 5225)(-3950 5225);
WIRE 16 -1 (-3950 5425)(-3950 5225);
WIRE 16 -1 (-3425 5425)(-3950 5425);
WIRE 16 -1 (-3950 5625)(-3950 5425);
WIRE 16 -1 (-3425 5625)(-3950 5625);
WIRE 16 -1 (-3950 5825)(-3950 5625);
WIRE 16 -1 (-3425 5825)(-3950 5825);
WIRE 16 -1 (-3950 6025)(-3950 5825);
WIRE 16 -1 (-3425 6025)(-3950 6025);
WIRE 16 -1 (2350 5950)(1850 5950);
WIRE 16 -1 (1850 5950)(1850 5575);
WIRE 16 -1 (2350 5575)(1850 5575);
DOT 1 (3300 5750);
DOT 1 (-3950 5425);
DOT 1 (-3950 2750);
DOT 1 (-3950 3425);
DOT 1 (-3950 3625);
DOT 1 (-3950 3825);
DOT 1 (-3950 4050);
DOT 1 (-3950 4250);
DOT 1 (-3950 4450);
DOT 1 (1850 5575);
DOT 1 (1975 6125);
DOT 1 (3300 6125);
DOT 1 (-825 3625);
DOT 1 (-3950 6225);
DOT 1 (-3950 6025);
DOT 1 (-3950 5825);
DOT 1 (-3950 5625);
DOT 1 (-3950 5225);
DOT 1 (-3950 5025);
DOT 1 (-3950 4825);
DOT 1 (-3950 4625);
DOT 1 (-825 3300);
DOT 1 (-3950 2975);
QUIT
